FILE_TYPE = MACRO_DRAWING;
SET COLOR_WIRE YELLOW;
SET COLOR_PROP MONO;
SET COLOR_DOT WHITE;
SET COLOR_ARC YELLOW;
SET COLOR_BODY GREEN;
SET COLOR_NOTE MONO;
SET PROP_DISPLAY VALUE;
SET PAGE_NUMBER P40;
FORCEADD GND..1
(-2625 450);
FORCEPROP 3 LASTPIN (-2625 500) SIG_NAME GND\g
J 0
(-2615 510);
DISPLAY 0.659574 (-2615 510);
PAINT MONO (-2615 510);
DISPLAY INVISIBLE (-2615 510);
FORCEPROP 1 LAST VOLTAGE 0.0V
J 0
(-2670 407);
DISPLAY 0.340426 (-2670 407);
PAINT SKYBLUE (-2670 407);
DISPLAY INVISIBLE (-2670 407);
FORCEPROP 1 LAST SIZE 1B
J 0
(-2550 400);
DISPLAY 1.170213 (-2550 400);
PAINT AQUA (-2550 400);
DISPLAY INVISIBLE (-2550 400);
FORCEPROP 2 LAST CDS_LIB mstr_symbols
J 0
(-2625 450);
PAINT ORANGE (-2625 450);
DISPLAY INVISIBLE (-2625 450);
FORCEPROP 1 LAST BODY_TYPE PLUMBING
J 0
(-2670 407);
DISPLAY 0.340426 (-2670 407);
PAINT GREEN (-2670 407);
DISPLAY INVISIBLE (-2670 407);
FORCEPROP 1 LAST PATH I11
J 0
(-2550 450);
DISPLAY 0.872340 (-2550 450);
PAINT AQUA (-2550 450);
DISPLAY INVISIBLE (-2550 450);
FORCEPROP 1 LAST HDL_POWER GND
J 0
(-2625 600);
DISPLAY 1.170213 (-2625 600);
PAINT GREEN (-2625 600);
DISPLAY INVISIBLE (-2625 600);
FORCEADD GND..1
(-775 450);
FORCEPROP 3 LASTPIN (-775 500) SIG_NAME GND\g
J 0
(-765 510);
DISPLAY 0.659574 (-765 510);
PAINT MONO (-765 510);
DISPLAY INVISIBLE (-765 510);
FORCEPROP 1 LAST VOLTAGE 0.0V
J 0
(-820 407);
DISPLAY 0.340426 (-820 407);
PAINT SKYBLUE (-820 407);
DISPLAY INVISIBLE (-820 407);
FORCEPROP 2 LAST CDS_LIB mstr_symbols
J 0
(-775 450);
PAINT ORANGE (-775 450);
DISPLAY INVISIBLE (-775 450);
FORCEPROP 1 LAST SIZE 1B
J 0
(-700 400);
DISPLAY 1.170213 (-700 400);
PAINT AQUA (-700 400);
DISPLAY INVISIBLE (-700 400);
FORCEPROP 1 LAST BODY_TYPE PLUMBING
J 0
(-820 407);
DISPLAY 0.340426 (-820 407);
PAINT GREEN (-820 407);
DISPLAY INVISIBLE (-820 407);
FORCEPROP 1 LAST PATH I13
J 0
(-700 450);
DISPLAY 0.872340 (-700 450);
PAINT AQUA (-700 450);
DISPLAY INVISIBLE (-700 450);
FORCEPROP 1 LAST HDL_POWER GND
J 0
(-775 600);
DISPLAY 1.170213 (-775 600);
PAINT GREEN (-775 600);
DISPLAY INVISIBLE (-775 600);
FORCEADD GND..1
(-2325 475);
FORCEPROP 3 LASTPIN (-2325 525) SIG_NAME GND\g
J 0
(-2315 535);
DISPLAY 0.659574 (-2315 535);
PAINT MONO (-2315 535);
DISPLAY INVISIBLE (-2315 535);
FORCEPROP 1 LAST VOLTAGE 0.0V
J 0
(-2370 432);
DISPLAY 0.340426 (-2370 432);
PAINT SKYBLUE (-2370 432);
DISPLAY INVISIBLE (-2370 432);
FORCEPROP 2 LAST CDS_LIB mstr_symbols
J 0
(-2325 475);
PAINT ORANGE (-2325 475);
DISPLAY INVISIBLE (-2325 475);
FORCEPROP 1 LAST SIZE 1B
J 0
(-2250 425);
DISPLAY 1.170213 (-2250 425);
PAINT AQUA (-2250 425);
DISPLAY INVISIBLE (-2250 425);
FORCEPROP 1 LAST BODY_TYPE PLUMBING
J 0
(-2370 432);
DISPLAY 0.340426 (-2370 432);
PAINT GREEN (-2370 432);
DISPLAY INVISIBLE (-2370 432);
FORCEPROP 1 LAST PATH I14
J 0
(-2250 475);
DISPLAY 0.872340 (-2250 475);
PAINT AQUA (-2250 475);
DISPLAY INVISIBLE (-2250 475);
FORCEPROP 1 LAST HDL_POWER GND
J 0
(-2325 625);
DISPLAY 1.170213 (-2325 625);
PAINT GREEN (-2325 625);
DISPLAY INVISIBLE (-2325 625);
FORCEADD SKX_EXT_B..23
(-7050 2575);
FORCEPROP 2 LASTPIN (-6450 1625) $PN H33
J 0
(-6440 1635);
DISPLAY 0.617021 (-6440 1635);
PAINT ORANGE (-6440 1635);
FORCEPROP 1 LAST LOCATION U5D1
J 0
(-7600 4825);
DISPLAY 0.617021 (-7600 4825);
PAINT AQUA (-7600 4825);
FORCEPROP 1 LAST PART_NUMBER TBD
J 0
(-7600 425);
DISPLAY 0.617021 (-7600 425);
PAINT BLUE (-7600 425);
FORCEPROP 1 LAST MATERIAL IC
J 0
(-7600 4775);
DISPLAY 0.617021 (-7600 4775);
PAINT SKYBLUE (-7600 4775);
FORCEPROP 2 LASTPIN (-7650 4525) $PN A42
J 2
(-7660 4535);
DISPLAY 0.617021 (-7660 4535);
PAINT ORANGE (-7660 4535);
FORCEPROP 2 LASTPIN (-7650 4475) $PN B43
J 2
(-7660 4485);
DISPLAY 0.617021 (-7660 4485);
PAINT ORANGE (-7660 4485);
FORCEPROP 2 LASTPIN (-7650 4425) $PN B5
J 2
(-7660 4435);
DISPLAY 0.617021 (-7660 4435);
PAINT ORANGE (-7660 4435);
FORCEPROP 2 LASTPIN (-7650 4375) $PN B79
J 2
(-7660 4385);
DISPLAY 0.617021 (-7660 4385);
PAINT ORANGE (-7660 4385);
FORCEPROP 2 LASTPIN (-7650 4325) $PN C4
J 2
(-7660 4335);
DISPLAY 0.617021 (-7660 4335);
PAINT ORANGE (-7660 4335);
FORCEPROP 2 LASTPIN (-7650 4225) $PN D3
J 2
(-7660 4235);
DISPLAY 0.617021 (-7660 4235);
PAINT ORANGE (-7660 4235);
FORCEPROP 2 LASTPIN (-7650 4175) $PN D81
J 2
(-7660 4185);
DISPLAY 0.617021 (-7660 4185);
PAINT ORANGE (-7660 4185);
FORCEPROP 2 LASTPIN (-7650 4125) $PN E82
J 2
(-7660 4135);
DISPLAY 0.617021 (-7660 4135);
PAINT ORANGE (-7660 4135);
FORCEPROP 2 LASTPIN (-7650 4075) $PN J86
J 2
(-7660 4085);
DISPLAY 0.617021 (-7660 4085);
PAINT ORANGE (-7660 4085);
FORCEPROP 2 LASTPIN (-7650 4025) $PN DY85
J 2
(-7660 4035);
DISPLAY 0.617021 (-7660 4035);
PAINT ORANGE (-7660 4035);
FORCEPROP 2 LASTPIN (-7650 3975) $PN EA84
J 2
(-7660 3985);
DISPLAY 0.617021 (-7660 3985);
PAINT ORANGE (-7660 3985);
FORCEPROP 2 LASTPIN (-7650 3925) $PN EB83
J 2
(-7660 3935);
DISPLAY 0.617021 (-7660 3935);
PAINT ORANGE (-7660 3935);
FORCEPROP 2 LASTPIN (-7650 3875) $PN DW2
J 2
(-7660 3885);
DISPLAY 0.617021 (-7660 3885);
PAINT ORANGE (-7660 3885);
FORCEPROP 2 LASTPIN (-7650 3825) $PN EC42
J 2
(-7660 3835);
DISPLAY 0.617021 (-7660 3835);
PAINT ORANGE (-7660 3835);
FORCEPROP 2 LASTPIN (-7650 3775) $PN EC6
J 2
(-7660 3785);
DISPLAY 0.617021 (-7660 3785);
PAINT ORANGE (-7660 3785);
FORCEPROP 2 LASTPIN (-7650 3725) $PN EC82
J 2
(-7660 3735);
DISPLAY 0.617021 (-7660 3735);
PAINT ORANGE (-7660 3735);
FORCEPROP 2 LASTPIN (-7650 3675) $PN ED41
J 2
(-7660 3685);
DISPLAY 0.617021 (-7660 3685);
PAINT ORANGE (-7660 3685);
FORCEPROP 2 LASTPIN (-7650 3625) $PN ED7
J 2
(-7660 3635);
DISPLAY 0.617021 (-7660 3635);
PAINT ORANGE (-7660 3635);
FORCEPROP 2 LASTPIN (-7650 3575) $PN ED81
J 2
(-7660 3585);
DISPLAY 0.617021 (-7660 3585);
PAINT ORANGE (-7660 3585);
FORCEPROP 2 LASTPIN (-7650 3525) $PN EE40
J 2
(-7660 3535);
DISPLAY 0.617021 (-7660 3535);
PAINT ORANGE (-7660 3535);
FORCEPROP 2 LASTPIN (-7650 3475) $PN EE8
J 2
(-7660 3485);
DISPLAY 0.617021 (-7660 3485);
PAINT ORANGE (-7660 3485);
FORCEPROP 2 LASTPIN (-7650 3425) $PN EE80
J 2
(-7660 3435);
DISPLAY 0.617021 (-7660 3435);
PAINT ORANGE (-7660 3435);
FORCEPROP 2 LASTPIN (-7650 3375) $PN ED69
J 2
(-7660 3385);
DISPLAY 0.617021 (-7660 3385);
PAINT ORANGE (-7660 3385);
FORCEPROP 2 LASTPIN (-7650 3325) $PN E66
J 2
(-7660 3335);
DISPLAY 0.617021 (-7660 3335);
PAINT ORANGE (-7660 3335);
FORCEPROP 2 LASTPIN (-7650 3275) $PN V11
J 2
(-7660 3285);
DISPLAY 0.617021 (-7660 3285);
PAINT ORANGE (-7660 3285);
FORCEPROP 2 LASTPIN (-7650 3225) $PN L8
J 2
(-7660 3235);
DISPLAY 0.617021 (-7660 3235);
PAINT ORANGE (-7660 3235);
FORCEPROP 2 LASTPIN (-7650 3175) $PN EA14
J 2
(-7660 3185);
DISPLAY 0.617021 (-7660 3185);
PAINT ORANGE (-7660 3185);
FORCEPROP 2 LASTPIN (-7650 3125) $PN DY63
J 2
(-7660 3135);
DISPLAY 0.617021 (-7660 3135);
PAINT ORANGE (-7660 3135);
FORCEPROP 2 LASTPIN (-7650 3075) $PN DY61
J 2
(-7660 3085);
DISPLAY 0.617021 (-7660 3085);
PAINT ORANGE (-7660 3085);
FORCEPROP 2 LASTPIN (-7650 3025) $PN DY59
J 2
(-7660 3035);
DISPLAY 0.617021 (-7660 3035);
PAINT ORANGE (-7660 3035);
FORCEPROP 2 LASTPIN (-7650 2975) $PN DY57
J 2
(-7660 2985);
DISPLAY 0.617021 (-7660 2985);
PAINT ORANGE (-7660 2985);
FORCEPROP 2 LASTPIN (-7650 2925) $PN DY55
J 2
(-7660 2935);
DISPLAY 0.617021 (-7660 2935);
PAINT ORANGE (-7660 2935);
FORCEPROP 2 LASTPIN (-7650 2875) $PN DY53
J 2
(-7660 2885);
DISPLAY 0.617021 (-7660 2885);
PAINT ORANGE (-7660 2885);
FORCEPROP 2 LASTPIN (-7650 2825) $PN DY51
J 2
(-7660 2835);
DISPLAY 0.617021 (-7660 2835);
PAINT ORANGE (-7660 2835);
FORCEPROP 2 LASTPIN (-7650 2775) $PN DY49
J 2
(-7660 2785);
DISPLAY 0.617021 (-7660 2785);
PAINT ORANGE (-7660 2785);
FORCEPROP 2 LASTPIN (-7650 2725) $PN DY47
J 2
(-7660 2735);
DISPLAY 0.617021 (-7660 2735);
PAINT ORANGE (-7660 2735);
FORCEPROP 2 LASTPIN (-7650 2675) $PN DY45
J 2
(-7660 2685);
DISPLAY 0.617021 (-7660 2685);
PAINT ORANGE (-7660 2685);
FORCEPROP 2 LASTPIN (-7650 2625) $PN DV19
J 2
(-7660 2635);
DISPLAY 0.617021 (-7660 2635);
PAINT ORANGE (-7660 2635);
FORCEPROP 2 LASTPIN (-7650 2575) $PN DP9
J 2
(-7660 2585);
DISPLAY 0.617021 (-7660 2585);
PAINT ORANGE (-7660 2585);
FORCEPROP 2 LASTPIN (-7650 2525) $PN DP63
J 2
(-7660 2535);
DISPLAY 0.617021 (-7660 2535);
PAINT ORANGE (-7660 2535);
FORCEPROP 2 LASTPIN (-7650 2475) $PN DP61
J 2
(-7660 2485);
DISPLAY 0.617021 (-7660 2485);
PAINT ORANGE (-7660 2485);
FORCEPROP 2 LASTPIN (-7650 2425) $PN DP59
J 2
(-7660 2435);
DISPLAY 0.617021 (-7660 2435);
PAINT ORANGE (-7660 2435);
FORCEPROP 2 LASTPIN (-7650 2375) $PN DP57
J 2
(-7660 2385);
DISPLAY 0.617021 (-7660 2385);
PAINT ORANGE (-7660 2385);
FORCEPROP 2 LASTPIN (-7650 2325) $PN DP55
J 2
(-7660 2335);
DISPLAY 0.617021 (-7660 2335);
PAINT ORANGE (-7660 2335);
FORCEPROP 2 LASTPIN (-7650 2275) $PN DP53
J 2
(-7660 2285);
DISPLAY 0.617021 (-7660 2285);
PAINT ORANGE (-7660 2285);
FORCEPROP 2 LASTPIN (-7650 2225) $PN DP51
J 2
(-7660 2235);
DISPLAY 0.617021 (-7660 2235);
PAINT ORANGE (-7660 2235);
FORCEPROP 2 LASTPIN (-7650 2175) $PN DP49
J 2
(-7660 2185);
DISPLAY 0.617021 (-7660 2185);
PAINT ORANGE (-7660 2185);
FORCEPROP 2 LASTPIN (-7650 2125) $PN DP47
J 2
(-7660 2135);
DISPLAY 0.617021 (-7660 2135);
PAINT ORANGE (-7660 2135);
FORCEPROP 2 LASTPIN (-7650 2075) $PN DP45
J 2
(-7660 2085);
DISPLAY 0.617021 (-7660 2085);
PAINT ORANGE (-7660 2085);
FORCEPROP 2 LASTPIN (-7650 2025) $PN DN18
J 2
(-7660 2035);
DISPLAY 0.617021 (-7660 2035);
PAINT ORANGE (-7660 2035);
FORCEPROP 2 LASTPIN (-7650 1975) $PN DL8
J 2
(-7660 1985);
DISPLAY 0.617021 (-7660 1985);
PAINT ORANGE (-7660 1985);
FORCEPROP 2 LASTPIN (-7650 1925) $PN DE62
J 2
(-7660 1935);
DISPLAY 0.617021 (-7660 1935);
PAINT ORANGE (-7660 1935);
FORCEPROP 2 LASTPIN (-7650 1875) $PN DE60
J 2
(-7660 1885);
DISPLAY 0.617021 (-7660 1885);
PAINT ORANGE (-7660 1885);
FORCEPROP 2 LASTPIN (-7650 1825) $PN DE58
J 2
(-7660 1835);
DISPLAY 0.617021 (-7660 1835);
PAINT ORANGE (-7660 1835);
FORCEPROP 2 LASTPIN (-7650 1775) $PN DE56
J 2
(-7660 1785);
DISPLAY 0.617021 (-7660 1785);
PAINT ORANGE (-7660 1785);
FORCEPROP 2 LASTPIN (-7650 1725) $PN DE54
J 2
(-7660 1735);
DISPLAY 0.617021 (-7660 1735);
PAINT ORANGE (-7660 1735);
FORCEPROP 2 LASTPIN (-7650 1675) $PN DE52
J 2
(-7660 1685);
DISPLAY 0.617021 (-7660 1685);
PAINT ORANGE (-7660 1685);
FORCEPROP 2 LASTPIN (-7650 1625) $PN DE50
J 2
(-7660 1635);
DISPLAY 0.617021 (-7660 1635);
PAINT ORANGE (-7660 1635);
FORCEPROP 2 LASTPIN (-7650 1575) $PN DE48
J 2
(-7660 1585);
DISPLAY 0.617021 (-7660 1585);
PAINT ORANGE (-7660 1585);
FORCEPROP 2 LASTPIN (-7650 1525) $PN CW6
J 2
(-7660 1535);
DISPLAY 0.617021 (-7660 1535);
PAINT ORANGE (-7660 1535);
FORCEPROP 2 LASTPIN (-7650 1475) $PN CG6
J 2
(-7660 1485);
DISPLAY 0.617021 (-7660 1485);
PAINT ORANGE (-7660 1485);
FORCEPROP 2 LASTPIN (-7650 1425) $PN AR6
J 2
(-7660 1435);
DISPLAY 0.617021 (-7660 1435);
PAINT ORANGE (-7660 1435);
FORCEPROP 2 LASTPIN (-7650 1375) $PN AJ4
J 2
(-7660 1385);
DISPLAY 0.617021 (-7660 1385);
PAINT ORANGE (-7660 1385);
FORCEPROP 2 LASTPIN (-7650 1325) $PN AC62
J 2
(-7660 1335);
DISPLAY 0.617021 (-7660 1335);
PAINT ORANGE (-7660 1335);
FORCEPROP 2 LASTPIN (-7650 1275) $PN AC60
J 2
(-7660 1285);
DISPLAY 0.617021 (-7660 1285);
PAINT ORANGE (-7660 1285);
FORCEPROP 2 LASTPIN (-7650 1225) $PN AC58
J 2
(-7660 1235);
DISPLAY 0.617021 (-7660 1235);
PAINT ORANGE (-7660 1235);
FORCEPROP 2 LASTPIN (-7650 1175) $PN A26
J 2
(-7660 1185);
DISPLAY 0.617021 (-7660 1185);
PAINT ORANGE (-7660 1185);
FORCEPROP 2 LASTPIN (-7650 1125) $PN A30
J 2
(-7660 1135);
DISPLAY 0.617021 (-7660 1135);
PAINT ORANGE (-7660 1135);
FORCEPROP 2 LASTPIN (-7650 1075) $PN A32
J 2
(-7660 1085);
DISPLAY 0.617021 (-7660 1085);
PAINT ORANGE (-7660 1085);
FORCEPROP 2 LASTPIN (-7650 1025) $PN A36
J 2
(-7660 1035);
DISPLAY 0.617021 (-7660 1035);
PAINT ORANGE (-7660 1035);
FORCEPROP 2 LASTPIN (-7650 975) $PN A38
J 2
(-7660 985);
DISPLAY 0.617021 (-7660 985);
PAINT ORANGE (-7660 985);
FORCEPROP 2 LASTPIN (-7650 925) $PN B25
J 2
(-7660 935);
DISPLAY 0.617021 (-7660 935);
PAINT ORANGE (-7660 935);
FORCEPROP 2 LASTPIN (-7650 875) $PN B31
J 2
(-7660 885);
DISPLAY 0.617021 (-7660 885);
PAINT ORANGE (-7660 885);
FORCEPROP 2 LASTPIN (-7650 825) $PN B37
J 2
(-7660 835);
DISPLAY 0.617021 (-7660 835);
PAINT ORANGE (-7660 835);
FORCEPROP 2 LASTPIN (-7650 775) $PN B71
J 2
(-7660 785);
DISPLAY 0.617021 (-7660 785);
PAINT ORANGE (-7660 785);
FORCEPROP 2 LASTPIN (-7650 725) $PN B75
J 2
(-7660 735);
DISPLAY 0.617021 (-7660 735);
PAINT ORANGE (-7660 735);
FORCEPROP 2 LASTPIN (-7650 675) $PN C8
J 2
(-7660 685);
DISPLAY 0.617021 (-7660 685);
PAINT ORANGE (-7660 685);
FORCEPROP 2 LASTPIN (-7650 625) $PN C10
J 2
(-7660 635);
DISPLAY 0.617021 (-7660 635);
PAINT ORANGE (-7660 635);
FORCEPROP 2 LASTPIN (-6450 4575) $PN C12
J 0
(-6440 4585);
DISPLAY 0.617021 (-6440 4585);
PAINT ORANGE (-6440 4585);
FORCEPROP 2 LASTPIN (-6450 4525) $PN C14
J 0
(-6440 4535);
DISPLAY 0.617021 (-6440 4535);
PAINT ORANGE (-6440 4535);
FORCEPROP 2 LASTPIN (-6450 4475) $PN C16
J 0
(-6440 4485);
DISPLAY 0.617021 (-6440 4485);
PAINT ORANGE (-6440 4485);
FORCEPROP 2 LASTPIN (-6450 4425) $PN C76
J 0
(-6440 4435);
DISPLAY 0.617021 (-6440 4435);
PAINT ORANGE (-6440 4435);
FORCEPROP 2 LASTPIN (-6450 4375) $PN C78
J 0
(-6440 4385);
DISPLAY 0.617021 (-6440 4385);
PAINT ORANGE (-6440 4385);
FORCEPROP 2 LASTPIN (-6450 4325) $PN CM27
J 0
(-6440 4335);
DISPLAY 0.617021 (-6440 4335);
PAINT ORANGE (-6440 4335);
FORCEPROP 2 LASTPIN (-6450 4275) $PN D11
J 0
(-6440 4285);
DISPLAY 0.617021 (-6440 4285);
PAINT ORANGE (-6440 4285);
FORCEPROP 2 LASTPIN (-6450 4225) $PN D13
J 0
(-6440 4235);
DISPLAY 0.617021 (-6440 4235);
PAINT ORANGE (-6440 4235);
FORCEPROP 2 LASTPIN (-6450 4175) $PN D25
J 0
(-6440 4185);
DISPLAY 0.617021 (-6440 4185);
PAINT ORANGE (-6440 4185);
FORCEPROP 2 LASTPIN (-6450 4125) $PN D27
J 0
(-6440 4135);
DISPLAY 0.617021 (-6440 4135);
PAINT ORANGE (-6440 4135);
FORCEPROP 2 LASTPIN (-6450 4075) $PN D29
J 0
(-6440 4085);
DISPLAY 0.617021 (-6440 4085);
PAINT ORANGE (-6440 4085);
FORCEPROP 2 LASTPIN (-6450 4025) $PN D31
J 0
(-6440 4035);
DISPLAY 0.617021 (-6440 4035);
PAINT ORANGE (-6440 4035);
FORCEPROP 2 LASTPIN (-6450 3975) $PN D33
J 0
(-6440 3985);
DISPLAY 0.617021 (-6440 3985);
PAINT ORANGE (-6440 3985);
FORCEPROP 2 LASTPIN (-6450 3925) $PN D35
J 0
(-6440 3935);
DISPLAY 0.617021 (-6440 3935);
PAINT ORANGE (-6440 3935);
FORCEPROP 2 LASTPIN (-6450 3875) $PN D37
J 0
(-6440 3885);
DISPLAY 0.617021 (-6440 3885);
PAINT ORANGE (-6440 3885);
FORCEPROP 2 LASTPIN (-6450 3825) $PN D39
J 0
(-6440 3835);
DISPLAY 0.617021 (-6440 3835);
PAINT ORANGE (-6440 3835);
FORCEPROP 2 LASTPIN (-6450 3775) $PN D41
J 0
(-6440 3785);
DISPLAY 0.617021 (-6440 3785);
PAINT ORANGE (-6440 3785);
FORCEPROP 2 LASTPIN (-6450 3725) $PN D43
J 0
(-6440 3735);
DISPLAY 0.617021 (-6440 3735);
PAINT ORANGE (-6440 3735);
FORCEPROP 2 LASTPIN (-6450 3675) $PN D77
J 0
(-6440 3685);
DISPLAY 0.617021 (-6440 3685);
PAINT ORANGE (-6440 3685);
FORCEPROP 2 LASTPIN (-6450 3625) $PN E6
J 0
(-6440 3635);
DISPLAY 0.617021 (-6440 3635);
PAINT ORANGE (-6440 3635);
FORCEPROP 2 LASTPIN (-6450 3575) $PN E8
J 0
(-6440 3585);
DISPLAY 0.617021 (-6440 3585);
PAINT ORANGE (-6440 3585);
FORCEPROP 2 LASTPIN (-6450 3525) $PN E16
J 0
(-6440 3535);
DISPLAY 0.617021 (-6440 3535);
PAINT ORANGE (-6440 3535);
FORCEPROP 2 LASTPIN (-6450 3475) $PN E18
J 0
(-6440 3485);
DISPLAY 0.617021 (-6440 3485);
PAINT ORANGE (-6440 3485);
FORCEPROP 2 LASTPIN (-6450 3425) $PN E20
J 0
(-6440 3435);
DISPLAY 0.617021 (-6440 3435);
PAINT ORANGE (-6440 3435);
FORCEPROP 2 LASTPIN (-6450 3375) $PN E22
J 0
(-6440 3385);
DISPLAY 0.617021 (-6440 3385);
PAINT ORANGE (-6440 3385);
FORCEPROP 2 LASTPIN (-6450 3325) $PN E72
J 0
(-6440 3335);
DISPLAY 0.617021 (-6440 3335);
PAINT ORANGE (-6440 3335);
FORCEPROP 2 LASTPIN (-6450 3275) $PN E74
J 0
(-6440 3285);
DISPLAY 0.617021 (-6440 3285);
PAINT ORANGE (-6440 3285);
FORCEPROP 2 LASTPIN (-6450 3225) $PN E76
J 0
(-6440 3235);
DISPLAY 0.617021 (-6440 3235);
PAINT ORANGE (-6440 3235);
FORCEPROP 2 LASTPIN (-6450 3175) $PN F5
J 0
(-6440 3185);
DISPLAY 0.617021 (-6440 3185);
PAINT ORANGE (-6440 3185);
FORCEPROP 2 LASTPIN (-6450 3125) $PN F17
J 0
(-6440 3135);
DISPLAY 0.617021 (-6440 3135);
PAINT ORANGE (-6440 3135);
FORCEPROP 2 LASTPIN (-6450 3075) $PN F19
J 0
(-6440 3085);
DISPLAY 0.617021 (-6440 3085);
PAINT ORANGE (-6440 3085);
FORCEPROP 2 LASTPIN (-6450 3025) $PN F25
J 0
(-6440 3035);
DISPLAY 0.617021 (-6440 3035);
PAINT ORANGE (-6440 3035);
FORCEPROP 2 LASTPIN (-6450 2975) $PN F31
J 0
(-6440 2985);
DISPLAY 0.617021 (-6440 2985);
PAINT ORANGE (-6440 2985);
FORCEPROP 2 LASTPIN (-6450 2925) $PN F37
J 0
(-6440 2935);
DISPLAY 0.617021 (-6440 2935);
PAINT ORANGE (-6440 2935);
FORCEPROP 2 LASTPIN (-6450 2875) $PN F43
J 0
(-6440 2885);
DISPLAY 0.617021 (-6440 2885);
PAINT ORANGE (-6440 2885);
FORCEPROP 2 LASTPIN (-6450 2825) $PN F67
J 0
(-6440 2835);
DISPLAY 0.617021 (-6440 2835);
PAINT ORANGE (-6440 2835);
FORCEPROP 2 LASTPIN (-6450 2775) $PN F69
J 0
(-6440 2785);
DISPLAY 0.617021 (-6440 2785);
PAINT ORANGE (-6440 2785);
FORCEPROP 2 LASTPIN (-6450 2675) $PN G8
J 0
(-6440 2685);
DISPLAY 0.617021 (-6440 2685);
PAINT ORANGE (-6440 2685);
FORCEPROP 2 LASTPIN (-6450 2625) $PN G22
J 0
(-6440 2635);
DISPLAY 0.617021 (-6440 2635);
PAINT ORANGE (-6440 2635);
FORCEPROP 2 LASTPIN (-6450 2575) $PN G24
J 0
(-6440 2585);
DISPLAY 0.617021 (-6440 2585);
PAINT ORANGE (-6440 2585);
FORCEPROP 2 LASTPIN (-6450 2525) $PN G26
J 0
(-6440 2535);
DISPLAY 0.617021 (-6440 2535);
PAINT ORANGE (-6440 2535);
FORCEPROP 2 LASTPIN (-6450 2475) $PN G30
J 0
(-6440 2485);
DISPLAY 0.617021 (-6440 2485);
PAINT ORANGE (-6440 2485);
FORCEPROP 2 LASTPIN (-6450 2425) $PN G32
J 0
(-6440 2435);
DISPLAY 0.617021 (-6440 2435);
PAINT ORANGE (-6440 2435);
FORCEPROP 2 LASTPIN (-6450 2375) $PN G36
J 0
(-6440 2385);
DISPLAY 0.617021 (-6440 2385);
PAINT ORANGE (-6440 2385);
FORCEPROP 2 LASTPIN (-6450 2325) $PN G38
J 0
(-6440 2335);
DISPLAY 0.617021 (-6440 2335);
PAINT ORANGE (-6440 2335);
FORCEPROP 2 LASTPIN (-6450 2275) $PN G42
J 0
(-6440 2285);
DISPLAY 0.617021 (-6440 2285);
PAINT ORANGE (-6440 2285);
FORCEPROP 2 LASTPIN (-6450 2225) $PN G66
J 0
(-6440 2235);
DISPLAY 0.617021 (-6440 2235);
PAINT ORANGE (-6440 2235);
FORCEPROP 2 LASTPIN (-6450 2175) $PN G70
J 0
(-6440 2185);
DISPLAY 0.617021 (-6440 2185);
PAINT ORANGE (-6440 2185);
FORCEPROP 2 LASTPIN (-6450 2125) $PN G76
J 0
(-6440 2135);
DISPLAY 0.617021 (-6440 2135);
PAINT ORANGE (-6440 2135);
FORCEPROP 2 LASTPIN (-6450 2075) $PN G78
J 0
(-6440 2085);
DISPLAY 0.617021 (-6440 2085);
PAINT ORANGE (-6440 2085);
FORCEPROP 2 LASTPIN (-6450 2025) $PN G80
J 0
(-6440 2035);
DISPLAY 0.617021 (-6440 2035);
PAINT ORANGE (-6440 2035);
FORCEPROP 2 LASTPIN (-6450 1975) $PN G82
J 0
(-6440 1985);
DISPLAY 0.617021 (-6440 1985);
PAINT ORANGE (-6440 1985);
FORCEPROP 2 LASTPIN (-6450 1925) $PN H3
J 0
(-6440 1935);
DISPLAY 0.617021 (-6440 1935);
PAINT ORANGE (-6440 1935);
FORCEPROP 2 LASTPIN (-6450 1875) $PN H11
J 0
(-6440 1885);
DISPLAY 0.617021 (-6440 1885);
PAINT ORANGE (-6440 1885);
FORCEPROP 2 LASTPIN (-6450 1825) $PN H25
J 0
(-6440 1835);
DISPLAY 0.617021 (-6440 1835);
PAINT ORANGE (-6440 1835);
FORCEPROP 2 LASTPIN (-6450 1775) $PN H27
J 0
(-6440 1785);
DISPLAY 0.617021 (-6440 1785);
PAINT ORANGE (-6440 1785);
FORCEPROP 2 LASTPIN (-6450 1725) $PN H29
J 0
(-6440 1735);
DISPLAY 0.617021 (-6440 1735);
PAINT ORANGE (-6440 1735);
FORCEPROP 2 LASTPIN (-6450 1675) $PN H31
J 0
(-6440 1685);
DISPLAY 0.617021 (-6440 1685);
PAINT ORANGE (-6440 1685);
FORCEPROP 2 LASTPIN (-6450 1575) $PN H35
J 0
(-6440 1585);
DISPLAY 0.617021 (-6440 1585);
PAINT ORANGE (-6440 1585);
FORCEPROP 2 LASTPIN (-6450 1525) $PN H37
J 0
(-6440 1535);
DISPLAY 0.617021 (-6440 1535);
PAINT ORANGE (-6440 1535);
FORCEPROP 2 LASTPIN (-6450 1475) $PN H39
J 0
(-6440 1485);
DISPLAY 0.617021 (-6440 1485);
PAINT ORANGE (-6440 1485);
FORCEPROP 2 LASTPIN (-6450 1425) $PN H41
J 0
(-6440 1435);
DISPLAY 0.617021 (-6440 1435);
PAINT ORANGE (-6440 1435);
FORCEPROP 2 LASTPIN (-6450 1375) $PN H65
J 0
(-6440 1385);
DISPLAY 0.617021 (-6440 1385);
PAINT ORANGE (-6440 1385);
FORCEPROP 2 LASTPIN (-6450 1325) $PN H71
J 0
(-6440 1335);
DISPLAY 0.617021 (-6440 1335);
PAINT ORANGE (-6440 1335);
FORCEPROP 2 LASTPIN (-6450 1275) $PN H75
J 0
(-6440 1285);
DISPLAY 0.617021 (-6440 1285);
PAINT ORANGE (-6440 1285);
FORCEPROP 2 LASTPIN (-6450 1225) $PN DN44
J 0
(-6440 1235);
DISPLAY 0.617021 (-6440 1235);
PAINT ORANGE (-6440 1235);
FORCEPROP 2 LASTPIN (-6450 1175) $PN J4
J 0
(-6440 1185);
DISPLAY 0.617021 (-6440 1185);
PAINT ORANGE (-6440 1185);
FORCEPROP 2 LASTPIN (-6450 1125) $PN J12
J 0
(-6440 1135);
DISPLAY 0.617021 (-6440 1135);
PAINT ORANGE (-6440 1135);
FORCEPROP 2 LASTPIN (-6450 1075) $PN J14
J 0
(-6440 1085);
DISPLAY 0.617021 (-6440 1085);
PAINT ORANGE (-6440 1085);
FORCEPROP 2 LASTPIN (-6450 1025) $PN J22
J 0
(-6440 1035);
DISPLAY 0.617021 (-6440 1035);
PAINT ORANGE (-6440 1035);
FORCEPROP 2 LASTPIN (-6450 975) $PN J26
J 0
(-6440 985);
DISPLAY 0.617021 (-6440 985);
PAINT ORANGE (-6440 985);
FORCEPROP 2 LASTPIN (-6450 925) $PN J28
J 0
(-6440 935);
DISPLAY 0.617021 (-6440 935);
PAINT ORANGE (-6440 935);
FORCEPROP 2 LASTPIN (-6450 875) $PN J32
J 0
(-6440 885);
DISPLAY 0.617021 (-6440 885);
PAINT ORANGE (-6440 885);
FORCEPROP 2 LASTPIN (-6450 825) $PN J34
J 0
(-6440 835);
DISPLAY 0.617021 (-6440 835);
PAINT ORANGE (-6440 835);
FORCEPROP 2 LASTPIN (-6450 775) $PN J38
J 0
(-6440 785);
DISPLAY 0.617021 (-6440 785);
PAINT ORANGE (-6440 785);
FORCEPROP 2 LASTPIN (-6450 725) $PN J40
J 0
(-6440 735);
DISPLAY 0.617021 (-6440 735);
PAINT ORANGE (-6440 735);
FORCEPROP 2 LASTPIN (-6450 675) $PN J72
J 0
(-6440 685);
DISPLAY 0.617021 (-6440 685);
PAINT ORANGE (-6440 685);
FORCEPROP 2 LASTPIN (-6450 625) $PN J74
J 0
(-6440 635);
DISPLAY 0.617021 (-6440 635);
PAINT ORANGE (-6440 635);
FORCEPROP 2 LASTPIN (-6450 2725) $PN G4
J 0
(-6440 2735);
DISPLAY 0.617021 (-6440 2735);
PAINT ORANGE (-6440 2735);
FORCEPROP 2 LASTPIN (-7650 4575) $PN B9
J 2
(-7660 4585);
DISPLAY 0.617021 (-7660 4585);
PAINT ORANGE (-7660 4585);
FORCEPROP 2 LASTPIN (-7650 4275) $PN C80
J 2
(-7660 4285);
DISPLAY 0.617021 (-7660 4285);
PAINT ORANGE (-7660 4285);
FORCEPROP 1 LAST PACK_TYPE BGA1
J 0
(-7600 4875);
PAINT SKYBLUE (-7600 4875);
DISPLAY INVISIBLE (-7600 4875);
FORCEPROP 2 LAST SEC_TYPE BGA1
J 0
(-7600 4875);
DISPLAY 1.021277 (-7600 4875);
PAINT ORANGE (-7600 4875);
DISPLAY INVISIBLE (-7600 4875);
FORCEPROP 2 LAST CDS_LIB chpset_lib
J 0
(-7050 2575);
PAINT ORANGE (-7050 2575);
DISPLAY INVISIBLE (-7050 2575);
FORCEPROP 2 LAST SEC 23
J 0
(-7600 4875);
DISPLAY 0.680851 (-7600 4875);
PAINT MONO (-7600 4875);
DISPLAY INVISIBLE (-7600 4875);
FORCEPROP 2 LAST CDS_LOCATION U5D1
J 0
(-7600 4825);
DISPLAY 0.617021 (-7600 4825);
PAINT AQUA (-7600 4825);
DISPLAY INVISIBLE (-7600 4825);
FORCEPROP 1 LAST PATH I20
J 0
(-7050 4775);
PAINT GREEN (-7050 4775);
DISPLAY INVISIBLE (-7050 4775);
FORCEPROP 0 LAST ROOM CPU0
J 0
(-7600 4925);
DISPLAY 1.021277 (-7600 4925);
PAINT ORANGE (-7600 4925);
DISPLAY INVISIBLE (-7600 4925);
FORCEADD SKX_EXT_B..24
(-5225 2575);
FORCEPROP 1 LAST LOCATION U5D1
J 0
(-5775 4825);
DISPLAY 0.617021 (-5775 4825);
PAINT AQUA (-5775 4825);
FORCEPROP 1 LAST PART_NUMBER TBD
J 0
(-5775 425);
DISPLAY 0.617021 (-5775 425);
PAINT BLUE (-5775 425);
FORCEPROP 1 LAST MATERIAL IC
J 0
(-5775 4775);
DISPLAY 0.617021 (-5775 4775);
PAINT SKYBLUE (-5775 4775);
FORCEPROP 2 LASTPIN (-5825 4575) $PN J76
J 2
(-5835 4585);
DISPLAY 0.617021 (-5835 4585);
PAINT ORANGE (-5835 4585);
FORCEPROP 2 LASTPIN (-5825 4525) $PN J82
J 2
(-5835 4535);
DISPLAY 0.617021 (-5835 4535);
PAINT ORANGE (-5835 4535);
FORCEPROP 2 LASTPIN (-5825 4475) $PN J84
J 2
(-5835 4485);
DISPLAY 0.617021 (-5835 4485);
PAINT ORANGE (-5835 4485);
FORCEPROP 2 LASTPIN (-5825 4425) $PN K1
J 2
(-5835 4435);
DISPLAY 0.617021 (-5835 4435);
PAINT ORANGE (-5835 4435);
FORCEPROP 2 LASTPIN (-5825 4325) $PN K13
J 2
(-5835 4335);
DISPLAY 0.617021 (-5835 4335);
PAINT ORANGE (-5835 4335);
FORCEPROP 2 LASTPIN (-5825 4275) $PN K17
J 2
(-5835 4285);
DISPLAY 0.617021 (-5835 4285);
PAINT ORANGE (-5835 4285);
FORCEPROP 2 LASTPIN (-5825 4225) $PN DB7
J 2
(-5835 4235);
DISPLAY 0.617021 (-5835 4235);
PAINT ORANGE (-5835 4235);
FORCEPROP 2 LASTPIN (-5825 4175) $PN K27
J 2
(-5835 4185);
DISPLAY 0.617021 (-5835 4185);
PAINT ORANGE (-5835 4185);
FORCEPROP 2 LASTPIN (-5825 4125) $PN K33
J 2
(-5835 4135);
DISPLAY 0.617021 (-5835 4135);
PAINT ORANGE (-5835 4135);
FORCEPROP 2 LASTPIN (-5825 4075) $PN K39
J 2
(-5835 4085);
DISPLAY 0.617021 (-5835 4085);
PAINT ORANGE (-5835 4085);
FORCEPROP 2 LASTPIN (-5825 4025) $PN K65
J 2
(-5835 4035);
DISPLAY 0.617021 (-5835 4035);
PAINT ORANGE (-5835 4035);
FORCEPROP 2 LASTPIN (-5825 3975) $PN K67
J 2
(-5835 3985);
DISPLAY 0.617021 (-5835 3985);
PAINT ORANGE (-5835 3985);
FORCEPROP 2 LASTPIN (-5825 3875) $PN K71
J 2
(-5835 3885);
DISPLAY 0.617021 (-5835 3885);
PAINT ORANGE (-5835 3885);
FORCEPROP 2 LASTPIN (-5825 3825) $PN K73
J 2
(-5835 3835);
DISPLAY 0.617021 (-5835 3835);
PAINT ORANGE (-5835 3835);
FORCEPROP 2 LASTPIN (-5825 3775) $PN K77
J 2
(-5835 3785);
DISPLAY 0.617021 (-5835 3785);
PAINT ORANGE (-5835 3785);
FORCEPROP 2 LASTPIN (-5825 3725) $PN K81
J 2
(-5835 3735);
DISPLAY 0.617021 (-5835 3735);
PAINT ORANGE (-5835 3735);
FORCEPROP 2 LASTPIN (-5825 3675) $PN K83
J 2
(-5835 3685);
DISPLAY 0.617021 (-5835 3685);
PAINT ORANGE (-5835 3685);
FORCEPROP 2 LASTPIN (-5825 3625) $PN K85
J 2
(-5835 3635);
DISPLAY 0.617021 (-5835 3635);
PAINT ORANGE (-5835 3635);
FORCEPROP 2 LASTPIN (-5825 3575) $PN L10
J 2
(-5835 3585);
DISPLAY 0.617021 (-5835 3585);
PAINT ORANGE (-5835 3585);
FORCEPROP 2 LASTPIN (-5825 3525) $PN L2
J 2
(-5835 3535);
DISPLAY 0.617021 (-5835 3535);
PAINT ORANGE (-5835 3535);
FORCEPROP 2 LASTPIN (-5825 3475) $PN L6
J 2
(-5835 3485);
DISPLAY 0.617021 (-5835 3485);
PAINT ORANGE (-5835 3485);
FORCEPROP 2 LASTPIN (-5825 3425) $PN L20
J 2
(-5835 3435);
DISPLAY 0.617021 (-5835 3435);
PAINT ORANGE (-5835 3435);
FORCEPROP 2 LASTPIN (-5825 3375) $PN L22
J 2
(-5835 3385);
DISPLAY 0.617021 (-5835 3385);
PAINT ORANGE (-5835 3385);
FORCEPROP 2 LASTPIN (-5825 3325) $PN L72
J 2
(-5835 3335);
DISPLAY 0.617021 (-5835 3335);
PAINT ORANGE (-5835 3335);
FORCEPROP 2 LASTPIN (-5825 3275) $PN L78
J 2
(-5835 3285);
DISPLAY 0.617021 (-5835 3285);
PAINT ORANGE (-5835 3285);
FORCEPROP 2 LASTPIN (-5825 3225) $PN L80
J 2
(-5835 3235);
DISPLAY 0.617021 (-5835 3235);
PAINT ORANGE (-5835 3235);
FORCEPROP 2 LASTPIN (-5825 3175) $PN L82
J 2
(-5835 3185);
DISPLAY 0.617021 (-5835 3185);
PAINT ORANGE (-5835 3185);
FORCEPROP 2 LASTPIN (-5825 3125) $PN BT9
J 2
(-5835 3135);
DISPLAY 0.617021 (-5835 3135);
PAINT ORANGE (-5835 3135);
FORCEPROP 2 LASTPIN (-5825 3075) $PN CT7
J 2
(-5835 3085);
DISPLAY 0.617021 (-5835 3085);
PAINT ORANGE (-5835 3085);
FORCEPROP 2 LASTPIN (-5825 3025) $PN M15
J 2
(-5835 3035);
DISPLAY 0.617021 (-5835 3035);
PAINT ORANGE (-5835 3035);
FORCEPROP 2 LASTPIN (-5825 2975) $PN M17
J 2
(-5835 2985);
DISPLAY 0.617021 (-5835 2985);
PAINT ORANGE (-5835 2985);
FORCEPROP 2 LASTPIN (-5825 2925) $PN M19
J 2
(-5835 2935);
DISPLAY 0.617021 (-5835 2935);
PAINT ORANGE (-5835 2935);
FORCEPROP 2 LASTPIN (-5825 2875) $PN M23
J 2
(-5835 2885);
DISPLAY 0.617021 (-5835 2885);
PAINT ORANGE (-5835 2885);
FORCEPROP 2 LASTPIN (-5825 2825) $PN M25
J 2
(-5835 2835);
DISPLAY 0.617021 (-5835 2835);
PAINT ORANGE (-5835 2835);
FORCEPROP 2 LASTPIN (-5825 2775) $PN M27
J 2
(-5835 2785);
DISPLAY 0.617021 (-5835 2785);
PAINT ORANGE (-5835 2785);
FORCEPROP 2 LASTPIN (-5825 2725) $PN M29
J 2
(-5835 2735);
DISPLAY 0.617021 (-5835 2735);
PAINT ORANGE (-5835 2735);
FORCEPROP 2 LASTPIN (-5825 2675) $PN M31
J 2
(-5835 2685);
DISPLAY 0.617021 (-5835 2685);
PAINT ORANGE (-5835 2685);
FORCEPROP 2 LASTPIN (-5825 2625) $PN M33
J 2
(-5835 2635);
DISPLAY 0.617021 (-5835 2635);
PAINT ORANGE (-5835 2635);
FORCEPROP 2 LASTPIN (-5825 2575) $PN M35
J 2
(-5835 2585);
DISPLAY 0.617021 (-5835 2585);
PAINT ORANGE (-5835 2585);
FORCEPROP 2 LASTPIN (-5825 2525) $PN M37
J 2
(-5835 2535);
DISPLAY 0.617021 (-5835 2535);
PAINT ORANGE (-5835 2535);
FORCEPROP 2 LASTPIN (-5825 2475) $PN M39
J 2
(-5835 2485);
DISPLAY 0.617021 (-5835 2485);
PAINT ORANGE (-5835 2485);
FORCEPROP 2 LASTPIN (-5825 2425) $PN M41
J 2
(-5835 2435);
DISPLAY 0.617021 (-5835 2435);
PAINT ORANGE (-5835 2435);
FORCEPROP 2 LASTPIN (-5825 2375) $PN M43
J 2
(-5835 2385);
DISPLAY 0.617021 (-5835 2385);
PAINT ORANGE (-5835 2385);
FORCEPROP 2 LASTPIN (-5825 2325) $PN M65
J 2
(-5835 2335);
DISPLAY 0.617021 (-5835 2335);
PAINT ORANGE (-5835 2335);
FORCEPROP 2 LASTPIN (-5825 2275) $PN M71
J 2
(-5835 2285);
DISPLAY 0.617021 (-5835 2285);
PAINT ORANGE (-5835 2285);
FORCEPROP 2 LASTPIN (-5825 2225) $PN M79
J 2
(-5835 2235);
DISPLAY 0.617021 (-5835 2235);
PAINT ORANGE (-5835 2235);
FORCEPROP 2 LASTPIN (-5825 2175) $PN M83
J 2
(-5835 2185);
DISPLAY 0.617021 (-5835 2185);
PAINT ORANGE (-5835 2185);
FORCEPROP 2 LASTPIN (-5825 2125) $PN M85
J 2
(-5835 2135);
DISPLAY 0.617021 (-5835 2135);
PAINT ORANGE (-5835 2135);
FORCEPROP 2 LASTPIN (-5825 2075) $PN DM19
J 2
(-5835 2085);
DISPLAY 0.617021 (-5835 2085);
PAINT ORANGE (-5835 2085);
FORCEPROP 2 LASTPIN (-5825 2025) $PN N20
J 2
(-5835 2035);
DISPLAY 0.617021 (-5835 2035);
PAINT ORANGE (-5835 2035);
FORCEPROP 2 LASTPIN (-5825 1975) $PN N22
J 2
(-5835 1985);
DISPLAY 0.617021 (-5835 1985);
PAINT ORANGE (-5835 1985);
FORCEPROP 2 LASTPIN (-5825 1925) $PN N6
J 2
(-5835 1935);
DISPLAY 0.617021 (-5835 1935);
PAINT ORANGE (-5835 1935);
FORCEPROP 2 LASTPIN (-5825 1875) $PN N66
J 2
(-5835 1885);
DISPLAY 0.617021 (-5835 1885);
PAINT ORANGE (-5835 1885);
FORCEPROP 2 LASTPIN (-5825 1825) $PN N70
J 2
(-5835 1835);
DISPLAY 0.617021 (-5835 1835);
PAINT ORANGE (-5835 1835);
FORCEPROP 2 LASTPIN (-5825 1775) $PN N72
J 2
(-5835 1785);
DISPLAY 0.617021 (-5835 1785);
PAINT ORANGE (-5835 1785);
FORCEPROP 2 LASTPIN (-5825 1725) $PN N74
J 2
(-5835 1735);
DISPLAY 0.617021 (-5835 1735);
PAINT ORANGE (-5835 1735);
FORCEPROP 2 LASTPIN (-5825 1675) $PN N76
J 2
(-5835 1685);
DISPLAY 0.617021 (-5835 1685);
PAINT ORANGE (-5835 1685);
FORCEPROP 2 LASTPIN (-5825 1625) $PN N78
J 2
(-5835 1635);
DISPLAY 0.617021 (-5835 1635);
PAINT ORANGE (-5835 1635);
FORCEPROP 2 LASTPIN (-5825 1575) $PN N4
J 2
(-5835 1585);
DISPLAY 0.617021 (-5835 1585);
PAINT ORANGE (-5835 1585);
FORCEPROP 2 LASTPIN (-5825 1525) $PN N8
J 2
(-5835 1535);
DISPLAY 0.617021 (-5835 1535);
PAINT ORANGE (-5835 1535);
FORCEPROP 2 LASTPIN (-5825 1475) $PN P11
J 2
(-5835 1485);
DISPLAY 0.617021 (-5835 1485);
PAINT ORANGE (-5835 1485);
FORCEPROP 2 LASTPIN (-5825 1425) $PN P15
J 2
(-5835 1435);
DISPLAY 0.617021 (-5835 1435);
PAINT ORANGE (-5835 1435);
FORCEPROP 2 LASTPIN (-5825 1375) $PN P27
J 2
(-5835 1385);
DISPLAY 0.617021 (-5835 1385);
PAINT ORANGE (-5835 1385);
FORCEPROP 2 LASTPIN (-5825 1325) $PN P33
J 2
(-5835 1335);
DISPLAY 0.617021 (-5835 1335);
PAINT ORANGE (-5835 1335);
FORCEPROP 2 LASTPIN (-5825 1275) $PN P39
J 2
(-5835 1285);
DISPLAY 0.617021 (-5835 1285);
PAINT ORANGE (-5835 1285);
FORCEPROP 2 LASTPIN (-5825 1225) $PN P67
J 2
(-5835 1235);
DISPLAY 0.617021 (-5835 1235);
PAINT ORANGE (-5835 1235);
FORCEPROP 2 LASTPIN (-5825 1175) $PN P69
J 2
(-5835 1185);
DISPLAY 0.617021 (-5835 1185);
PAINT ORANGE (-5835 1185);
FORCEPROP 2 LASTPIN (-5825 1125) $PN P71
J 2
(-5835 1135);
DISPLAY 0.617021 (-5835 1135);
PAINT ORANGE (-5835 1135);
FORCEPROP 2 LASTPIN (-5825 1075) $PN P81
J 2
(-5835 1085);
DISPLAY 0.617021 (-5835 1085);
PAINT ORANGE (-5835 1085);
FORCEPROP 2 LASTPIN (-5825 1025) $PN P83
J 2
(-5835 1035);
DISPLAY 0.617021 (-5835 1035);
PAINT ORANGE (-5835 1035);
FORCEPROP 2 LASTPIN (-5825 975) $PN R14
J 2
(-5835 985);
DISPLAY 0.617021 (-5835 985);
PAINT ORANGE (-5835 985);
FORCEPROP 2 LASTPIN (-5825 925) $PN R18
J 2
(-5835 935);
DISPLAY 0.617021 (-5835 935);
PAINT ORANGE (-5835 935);
FORCEPROP 2 LASTPIN (-5825 875) $PN R2
J 2
(-5835 885);
DISPLAY 0.617021 (-5835 885);
PAINT ORANGE (-5835 885);
FORCEPROP 2 LASTPIN (-5825 825) $PN R4
J 2
(-5835 835);
DISPLAY 0.617021 (-5835 835);
PAINT ORANGE (-5835 835);
FORCEPROP 2 LASTPIN (-5825 775) $PN R22
J 2
(-5835 785);
DISPLAY 0.617021 (-5835 785);
PAINT ORANGE (-5835 785);
FORCEPROP 2 LASTPIN (-5825 725) $PN R26
J 2
(-5835 735);
DISPLAY 0.617021 (-5835 735);
PAINT ORANGE (-5835 735);
FORCEPROP 2 LASTPIN (-5825 675) $PN R28
J 2
(-5835 685);
DISPLAY 0.617021 (-5835 685);
PAINT ORANGE (-5835 685);
FORCEPROP 2 LASTPIN (-5825 625) $PN R32
J 2
(-5835 635);
DISPLAY 0.617021 (-5835 635);
PAINT ORANGE (-5835 635);
FORCEPROP 2 LASTPIN (-4625 4575) $PN R34
J 0
(-4615 4585);
DISPLAY 0.617021 (-4615 4585);
PAINT ORANGE (-4615 4585);
FORCEPROP 2 LASTPIN (-4625 4525) $PN R38
J 0
(-4615 4535);
DISPLAY 0.617021 (-4615 4535);
PAINT ORANGE (-4615 4535);
FORCEPROP 2 LASTPIN (-4625 4475) $PN R40
J 0
(-4615 4485);
DISPLAY 0.617021 (-4615 4485);
PAINT ORANGE (-4615 4485);
FORCEPROP 2 LASTPIN (-4625 4425) $PN R68
J 0
(-4615 4435);
DISPLAY 0.617021 (-4615 4435);
PAINT ORANGE (-4615 4435);
FORCEPROP 2 LASTPIN (-4625 4375) $PN R72
J 0
(-4615 4385);
DISPLAY 0.617021 (-4615 4385);
PAINT ORANGE (-4615 4385);
FORCEPROP 2 LASTPIN (-4625 4325) $PN R78
J 0
(-4615 4335);
DISPLAY 0.617021 (-4615 4335);
PAINT ORANGE (-4615 4335);
FORCEPROP 2 LASTPIN (-4625 4275) $PN R86
J 0
(-4615 4285);
DISPLAY 0.617021 (-4615 4285);
PAINT ORANGE (-4615 4285);
FORCEPROP 2 LASTPIN (-4625 4225) $PN T13
J 0
(-4615 4235);
DISPLAY 0.617021 (-4615 4235);
PAINT ORANGE (-4615 4235);
FORCEPROP 2 LASTPIN (-4625 4175) $PN T17
J 0
(-4615 4185);
DISPLAY 0.617021 (-4615 4185);
PAINT ORANGE (-4615 4185);
FORCEPROP 2 LASTPIN (-4625 4125) $PN T25
J 0
(-4615 4135);
DISPLAY 0.617021 (-4615 4135);
PAINT ORANGE (-4615 4135);
FORCEPROP 2 LASTPIN (-4625 4075) $PN T29
J 0
(-4615 4085);
DISPLAY 0.617021 (-4615 4085);
PAINT ORANGE (-4615 4085);
FORCEPROP 2 LASTPIN (-4625 4025) $PN T31
J 0
(-4615 4035);
DISPLAY 0.617021 (-4615 4035);
PAINT ORANGE (-4615 4035);
FORCEPROP 2 LASTPIN (-4625 3975) $PN T35
J 0
(-4615 3985);
DISPLAY 0.617021 (-4615 3985);
PAINT ORANGE (-4615 3985);
FORCEPROP 2 LASTPIN (-4625 3875) $PN T41
J 0
(-4615 3885);
DISPLAY 0.617021 (-4615 3885);
PAINT ORANGE (-4615 3885);
FORCEPROP 2 LASTPIN (-4625 3825) $PN T65
J 0
(-4615 3835);
DISPLAY 0.617021 (-4615 3835);
PAINT ORANGE (-4615 3835);
FORCEPROP 2 LASTPIN (-4625 3775) $PN T73
J 0
(-4615 3785);
DISPLAY 0.617021 (-4615 3785);
PAINT ORANGE (-4615 3785);
FORCEPROP 2 LASTPIN (-4625 3725) $PN T77
J 0
(-4615 3735);
DISPLAY 0.617021 (-4615 3735);
PAINT ORANGE (-4615 3735);
FORCEPROP 2 LASTPIN (-4625 3675) $PN T83
J 0
(-4615 3685);
DISPLAY 0.617021 (-4615 3685);
PAINT ORANGE (-4615 3685);
FORCEPROP 2 LASTPIN (-4625 3625) $PN T85
J 0
(-4615 3635);
DISPLAY 0.617021 (-4615 3635);
PAINT ORANGE (-4615 3635);
FORCEPROP 2 LASTPIN (-4625 3575) $PN U2
J 0
(-4615 3585);
DISPLAY 0.617021 (-4615 3585);
PAINT ORANGE (-4615 3585);
FORCEPROP 2 LASTPIN (-4625 3525) $PN U4
J 0
(-4615 3535);
DISPLAY 0.617021 (-4615 3535);
PAINT ORANGE (-4615 3535);
FORCEPROP 2 LASTPIN (-4625 3475) $PN U6
J 0
(-4615 3485);
DISPLAY 0.617021 (-4615 3485);
PAINT ORANGE (-4615 3485);
FORCEPROP 2 LASTPIN (-4625 3425) $PN U20
J 0
(-4615 3435);
DISPLAY 0.617021 (-4615 3435);
PAINT ORANGE (-4615 3435);
FORCEPROP 2 LASTPIN (-4625 3375) $PN U22
J 0
(-4615 3385);
DISPLAY 0.617021 (-4615 3385);
PAINT ORANGE (-4615 3385);
FORCEPROP 2 LASTPIN (-4625 3325) $PN U24
J 0
(-4615 3335);
DISPLAY 0.617021 (-4615 3335);
PAINT ORANGE (-4615 3335);
FORCEPROP 2 LASTPIN (-4625 3275) $PN U30
J 0
(-4615 3285);
DISPLAY 0.617021 (-4615 3285);
PAINT ORANGE (-4615 3285);
FORCEPROP 2 LASTPIN (-4625 3225) $PN U36
J 0
(-4615 3235);
DISPLAY 0.617021 (-4615 3235);
PAINT ORANGE (-4615 3235);
FORCEPROP 2 LASTPIN (-4625 3175) $PN U42
J 0
(-4615 3185);
DISPLAY 0.617021 (-4615 3185);
PAINT ORANGE (-4615 3185);
FORCEPROP 2 LASTPIN (-4625 3125) $PN U68
J 0
(-4615 3135);
DISPLAY 0.617021 (-4615 3135);
PAINT ORANGE (-4615 3135);
FORCEPROP 2 LASTPIN (-4625 3075) $PN U70
J 0
(-4615 3085);
DISPLAY 0.617021 (-4615 3085);
PAINT ORANGE (-4615 3085);
FORCEPROP 2 LASTPIN (-4625 3025) $PN U74
J 0
(-4615 3035);
DISPLAY 0.617021 (-4615 3035);
PAINT ORANGE (-4615 3035);
FORCEPROP 2 LASTPIN (-4625 2975) $PN U76
J 0
(-4615 2985);
DISPLAY 0.617021 (-4615 2985);
PAINT ORANGE (-4615 2985);
FORCEPROP 2 LASTPIN (-4625 2925) $PN U78
J 0
(-4615 2935);
DISPLAY 0.617021 (-4615 2935);
PAINT ORANGE (-4615 2935);
FORCEPROP 2 LASTPIN (-4625 2875) $PN U80
J 0
(-4615 2885);
DISPLAY 0.617021 (-4615 2885);
PAINT ORANGE (-4615 2885);
FORCEPROP 2 LASTPIN (-4625 2825) $PN U86
J 0
(-4615 2835);
DISPLAY 0.617021 (-4615 2835);
PAINT ORANGE (-4615 2835);
FORCEPROP 2 LASTPIN (-4625 2775) $PN V1
J 0
(-4615 2785);
DISPLAY 0.617021 (-4615 2785);
PAINT ORANGE (-4615 2785);
FORCEPROP 2 LASTPIN (-4625 2725) $PN V5
J 0
(-4615 2735);
DISPLAY 0.617021 (-4615 2735);
PAINT ORANGE (-4615 2735);
FORCEPROP 2 LASTPIN (-4625 2675) $PN V9
J 0
(-4615 2685);
DISPLAY 0.617021 (-4615 2685);
PAINT ORANGE (-4615 2685);
FORCEPROP 2 LASTPIN (-4625 2625) $PN V13
J 0
(-4615 2635);
DISPLAY 0.617021 (-4615 2635);
PAINT ORANGE (-4615 2635);
FORCEPROP 2 LASTPIN (-4625 2575) $PN V15
J 0
(-4615 2585);
DISPLAY 0.617021 (-4615 2585);
PAINT ORANGE (-4615 2585);
FORCEPROP 2 LASTPIN (-4625 2525) $PN V21
J 0
(-4615 2535);
DISPLAY 0.617021 (-4615 2535);
PAINT ORANGE (-4615 2535);
FORCEPROP 2 LASTPIN (-4625 2475) $PN V23
J 0
(-4615 2485);
DISPLAY 0.617021 (-4615 2485);
PAINT ORANGE (-4615 2485);
FORCEPROP 2 LASTPIN (-4625 2425) $PN V43
J 0
(-4615 2435);
DISPLAY 0.617021 (-4615 2435);
PAINT ORANGE (-4615 2435);
FORCEPROP 2 LASTPIN (-4625 2375) $PN V73
J 0
(-4615 2385);
DISPLAY 0.617021 (-4615 2385);
PAINT ORANGE (-4615 2385);
FORCEPROP 2 LASTPIN (-4625 2325) $PN V75
J 0
(-4615 2335);
DISPLAY 0.617021 (-4615 2335);
PAINT ORANGE (-4615 2335);
FORCEPROP 2 LASTPIN (-4625 2275) $PN V77
J 0
(-4615 2285);
DISPLAY 0.617021 (-4615 2285);
PAINT ORANGE (-4615 2285);
FORCEPROP 2 LASTPIN (-4625 2225) $PN V83
J 0
(-4615 2235);
DISPLAY 0.617021 (-4615 2235);
PAINT ORANGE (-4615 2235);
FORCEPROP 2 LASTPIN (-4625 2175) $PN W8
J 0
(-4615 2185);
DISPLAY 0.617021 (-4615 2185);
PAINT ORANGE (-4615 2185);
FORCEPROP 2 LASTPIN (-4625 2125) $PN AC56
J 0
(-4615 2135);
DISPLAY 0.617021 (-4615 2135);
PAINT ORANGE (-4615 2135);
FORCEPROP 2 LASTPIN (-4625 2075) $PN W12
J 0
(-4615 2085);
DISPLAY 0.617021 (-4615 2085);
PAINT ORANGE (-4615 2085);
FORCEPROP 2 LASTPIN (-4625 2025) $PN W22
J 0
(-4615 2035);
DISPLAY 0.617021 (-4615 2035);
PAINT ORANGE (-4615 2035);
FORCEPROP 2 LASTPIN (-4625 1975) $PN W24
J 0
(-4615 1985);
DISPLAY 0.617021 (-4615 1985);
PAINT ORANGE (-4615 1985);
FORCEPROP 2 LASTPIN (-4625 1925) $PN W26
J 0
(-4615 1935);
DISPLAY 0.617021 (-4615 1935);
PAINT ORANGE (-4615 1935);
FORCEPROP 2 LASTPIN (-4625 1875) $PN W28
J 0
(-4615 1885);
DISPLAY 0.617021 (-4615 1885);
PAINT ORANGE (-4615 1885);
FORCEPROP 2 LASTPIN (-4625 1825) $PN W30
J 0
(-4615 1835);
DISPLAY 0.617021 (-4615 1835);
PAINT ORANGE (-4615 1835);
FORCEPROP 2 LASTPIN (-4625 1775) $PN W32
J 0
(-4615 1785);
DISPLAY 0.617021 (-4615 1785);
PAINT ORANGE (-4615 1785);
FORCEPROP 2 LASTPIN (-4625 1725) $PN W34
J 0
(-4615 1735);
DISPLAY 0.617021 (-4615 1735);
PAINT ORANGE (-4615 1735);
FORCEPROP 2 LASTPIN (-4625 1675) $PN W36
J 0
(-4615 1685);
DISPLAY 0.617021 (-4615 1685);
PAINT ORANGE (-4615 1685);
FORCEPROP 2 LASTPIN (-4625 1625) $PN W38
J 0
(-4615 1635);
DISPLAY 0.617021 (-4615 1635);
PAINT ORANGE (-4615 1635);
FORCEPROP 2 LASTPIN (-4625 1575) $PN W40
J 0
(-4615 1585);
DISPLAY 0.617021 (-4615 1585);
PAINT ORANGE (-4615 1585);
FORCEPROP 2 LASTPIN (-4625 1525) $PN W42
J 0
(-4615 1535);
DISPLAY 0.617021 (-4615 1535);
PAINT ORANGE (-4615 1535);
FORCEPROP 2 LASTPIN (-4625 1475) $PN W68
J 0
(-4615 1485);
DISPLAY 0.617021 (-4615 1485);
PAINT ORANGE (-4615 1485);
FORCEPROP 2 LASTPIN (-4625 1425) $PN W74
J 0
(-4615 1435);
DISPLAY 0.617021 (-4615 1435);
PAINT ORANGE (-4615 1435);
FORCEPROP 2 LASTPIN (-4625 1375) $PN W78
J 0
(-4615 1385);
DISPLAY 0.617021 (-4615 1385);
PAINT ORANGE (-4615 1385);
FORCEPROP 2 LASTPIN (-4625 1325) $PN W82
J 0
(-4615 1335);
DISPLAY 0.617021 (-4615 1335);
PAINT ORANGE (-4615 1335);
FORCEPROP 2 LASTPIN (-4625 1275) $PN Y15
J 0
(-4615 1285);
DISPLAY 0.617021 (-4615 1285);
PAINT ORANGE (-4615 1285);
FORCEPROP 2 LASTPIN (-4625 1225) $PN Y17
J 0
(-4615 1235);
DISPLAY 0.617021 (-4615 1235);
PAINT ORANGE (-4615 1235);
FORCEPROP 2 LASTPIN (-4625 1175) $PN Y5
J 0
(-4615 1185);
DISPLAY 0.617021 (-4615 1185);
PAINT ORANGE (-4615 1185);
FORCEPROP 2 LASTPIN (-4625 1125) $PN Y67
J 0
(-4615 1135);
DISPLAY 0.617021 (-4615 1135);
PAINT ORANGE (-4615 1135);
FORCEPROP 2 LASTPIN (-4625 1075) $PN Y7
J 0
(-4615 1085);
DISPLAY 0.617021 (-4615 1085);
PAINT ORANGE (-4615 1085);
FORCEPROP 2 LASTPIN (-4625 1025) $PN Y9
J 0
(-4615 1035);
DISPLAY 0.617021 (-4615 1035);
PAINT ORANGE (-4615 1035);
FORCEPROP 2 LASTPIN (-4625 975) $PN Y71
J 0
(-4615 985);
DISPLAY 0.617021 (-4615 985);
PAINT ORANGE (-4615 985);
FORCEPROP 2 LASTPIN (-4625 925) $PN Y73
J 0
(-4615 935);
DISPLAY 0.617021 (-4615 935);
PAINT ORANGE (-4615 935);
FORCEPROP 2 LASTPIN (-4625 875) $PN Y79
J 0
(-4615 885);
DISPLAY 0.617021 (-4615 885);
PAINT ORANGE (-4615 885);
FORCEPROP 2 LASTPIN (-4625 825) $PN Y81
J 0
(-4615 835);
DISPLAY 0.617021 (-4615 835);
PAINT ORANGE (-4615 835);
FORCEPROP 2 LASTPIN (-4625 775) $PN Y83
J 0
(-4615 785);
DISPLAY 0.617021 (-4615 785);
PAINT ORANGE (-4615 785);
FORCEPROP 2 LASTPIN (-4625 725) $PN Y85
J 0
(-4615 735);
DISPLAY 0.617021 (-4615 735);
PAINT ORANGE (-4615 735);
FORCEPROP 2 LASTPIN (-4625 675) $PN AA4
J 0
(-4615 685);
DISPLAY 0.617021 (-4615 685);
PAINT ORANGE (-4615 685);
FORCEPROP 2 LASTPIN (-4625 625) $PN AA16
J 0
(-4615 635);
DISPLAY 0.617021 (-4615 635);
PAINT ORANGE (-4615 635);
FORCEPROP 2 LASTPIN (-5825 4375) $PN K11
J 2
(-5835 4385);
DISPLAY 0.617021 (-5835 4385);
PAINT ORANGE (-5835 4385);
FORCEPROP 2 LASTPIN (-5825 3925) $PN K69
J 2
(-5835 3935);
DISPLAY 0.617021 (-5835 3935);
PAINT ORANGE (-5835 3935);
FORCEPROP 2 LASTPIN (-4625 3925) $PN T37
J 0
(-4615 3935);
DISPLAY 0.617021 (-4615 3935);
PAINT ORANGE (-4615 3935);
FORCEPROP 1 LAST PACK_TYPE BGA1
J 0
(-5775 4875);
PAINT SKYBLUE (-5775 4875);
DISPLAY INVISIBLE (-5775 4875);
FORCEPROP 2 LAST SEC_TYPE BGA1
J 0
(-5775 4875);
DISPLAY 1.021277 (-5775 4875);
PAINT ORANGE (-5775 4875);
DISPLAY INVISIBLE (-5775 4875);
FORCEPROP 2 LAST CDS_LIB chpset_lib
J 0
(-5225 2575);
PAINT ORANGE (-5225 2575);
DISPLAY INVISIBLE (-5225 2575);
FORCEPROP 2 LAST SEC 24
J 0
(-5775 4875);
DISPLAY 0.680851 (-5775 4875);
PAINT MONO (-5775 4875);
DISPLAY INVISIBLE (-5775 4875);
FORCEPROP 2 LAST CDS_LOCATION U5D1
J 0
(-5775 4825);
DISPLAY 0.617021 (-5775 4825);
PAINT AQUA (-5775 4825);
DISPLAY INVISIBLE (-5775 4825);
FORCEPROP 1 LAST PATH I21
J 0
(-5225 4775);
PAINT GREEN (-5225 4775);
DISPLAY INVISIBLE (-5225 4775);
FORCEPROP 0 LAST ROOM CPU0
J 0
(-5775 4925);
DISPLAY 1.021277 (-5775 4925);
PAINT ORANGE (-5775 4925);
DISPLAY INVISIBLE (-5775 4925);
FORCEADD SKX_EXT_B..25
(-3400 2575);
FORCEPROP 1 LAST LOCATION U5D1
J 0
(-3950 4825);
DISPLAY 0.617021 (-3950 4825);
PAINT AQUA (-3950 4825);
FORCEPROP 1 LAST PART_NUMBER TBD
J 0
(-3950 425);
DISPLAY 0.617021 (-3950 425);
PAINT BLUE (-3950 425);
FORCEPROP 1 LAST MATERIAL IC
J 0
(-3950 4775);
DISPLAY 0.617021 (-3950 4775);
PAINT SKYBLUE (-3950 4775);
FORCEPROP 2 LASTPIN (-4000 4575) $PN AA18
J 2
(-4010 4585);
DISPLAY 0.617021 (-4010 4585);
PAINT ORANGE (-4010 4585);
FORCEPROP 2 LASTPIN (-4000 4525) $PN AA22
J 2
(-4010 4535);
DISPLAY 0.617021 (-4010 4535);
PAINT ORANGE (-4010 4535);
FORCEPROP 2 LASTPIN (-4000 4475) $PN AA24
J 2
(-4010 4485);
DISPLAY 0.617021 (-4010 4485);
PAINT ORANGE (-4010 4485);
FORCEPROP 2 LASTPIN (-4000 4425) $PN AA30
J 2
(-4010 4435);
DISPLAY 0.617021 (-4010 4435);
PAINT ORANGE (-4010 4435);
FORCEPROP 2 LASTPIN (-4000 4375) $PN AA36
J 2
(-4010 4385);
DISPLAY 0.617021 (-4010 4385);
PAINT ORANGE (-4010 4385);
FORCEPROP 2 LASTPIN (-4000 4325) $PN AA42
J 2
(-4010 4335);
DISPLAY 0.617021 (-4010 4335);
PAINT ORANGE (-4010 4335);
FORCEPROP 2 LASTPIN (-4000 4275) $PN AA64
J 2
(-4010 4285);
DISPLAY 0.617021 (-4010 4285);
PAINT ORANGE (-4010 4285);
FORCEPROP 2 LASTPIN (-4000 4225) $PN AA66
J 2
(-4010 4235);
DISPLAY 0.617021 (-4010 4235);
PAINT ORANGE (-4010 4235);
FORCEPROP 2 LASTPIN (-4000 4175) $PN AA68
J 2
(-4010 4185);
DISPLAY 0.617021 (-4010 4185);
PAINT ORANGE (-4010 4185);
FORCEPROP 2 LASTPIN (-4000 4125) $PN AA76
J 2
(-4010 4135);
DISPLAY 0.617021 (-4010 4135);
PAINT ORANGE (-4010 4135);
FORCEPROP 2 LASTPIN (-4000 4075) $PN AA78
J 2
(-4010 4085);
DISPLAY 0.617021 (-4010 4085);
PAINT ORANGE (-4010 4085);
FORCEPROP 2 LASTPIN (-4000 4025) $PN AA80
J 2
(-4010 4035);
DISPLAY 0.617021 (-4010 4035);
PAINT ORANGE (-4010 4035);
FORCEPROP 2 LASTPIN (-4000 3975) $PN AA82
J 2
(-4010 3985);
DISPLAY 0.617021 (-4010 3985);
PAINT ORANGE (-4010 3985);
FORCEPROP 2 LASTPIN (-4000 3925) $PN AB1
J 2
(-4010 3935);
DISPLAY 0.617021 (-4010 3935);
PAINT ORANGE (-4010 3935);
FORCEPROP 2 LASTPIN (-4000 3875) $PN AB5
J 2
(-4010 3885);
DISPLAY 0.617021 (-4010 3885);
PAINT ORANGE (-4010 3885);
FORCEPROP 2 LASTPIN (-4000 3825) $PN AB11
J 2
(-4010 3835);
DISPLAY 0.617021 (-4010 3835);
PAINT ORANGE (-4010 3835);
FORCEPROP 2 LASTPIN (-4000 3775) $PN AB21
J 2
(-4010 3785);
DISPLAY 0.617021 (-4010 3785);
PAINT ORANGE (-4010 3785);
FORCEPROP 2 LASTPIN (-4000 3725) $PN AB23
J 2
(-4010 3735);
DISPLAY 0.617021 (-4010 3735);
PAINT ORANGE (-4010 3735);
FORCEPROP 2 LASTPIN (-4000 3675) $PN AB25
J 2
(-4010 3685);
DISPLAY 0.617021 (-4010 3685);
PAINT ORANGE (-4010 3685);
FORCEPROP 2 LASTPIN (-4000 3625) $PN AB29
J 2
(-4010 3635);
DISPLAY 0.617021 (-4010 3635);
PAINT ORANGE (-4010 3635);
FORCEPROP 2 LASTPIN (-4000 3575) $PN AB31
J 2
(-4010 3585);
DISPLAY 0.617021 (-4010 3585);
PAINT ORANGE (-4010 3585);
FORCEPROP 2 LASTPIN (-4000 3525) $PN AB35
J 2
(-4010 3535);
DISPLAY 0.617021 (-4010 3535);
PAINT ORANGE (-4010 3535);
FORCEPROP 2 LASTPIN (-4000 3475) $PN AB37
J 2
(-4010 3485);
DISPLAY 0.617021 (-4010 3485);
PAINT ORANGE (-4010 3485);
FORCEPROP 2 LASTPIN (-4000 3425) $PN AB41
J 2
(-4010 3435);
DISPLAY 0.617021 (-4010 3435);
PAINT ORANGE (-4010 3435);
FORCEPROP 2 LASTPIN (-4000 3375) $PN AB65
J 2
(-4010 3385);
DISPLAY 0.617021 (-4010 3385);
PAINT ORANGE (-4010 3385);
FORCEPROP 2 LASTPIN (-4000 3325) $PN AB69
J 2
(-4010 3335);
DISPLAY 0.617021 (-4010 3335);
PAINT ORANGE (-4010 3335);
FORCEPROP 2 LASTPIN (-4000 3275) $PN AB73
J 2
(-4010 3285);
DISPLAY 0.617021 (-4010 3285);
PAINT ORANGE (-4010 3285);
FORCEPROP 2 LASTPIN (-4000 3225) $PN AB79
J 2
(-4010 3235);
DISPLAY 0.617021 (-4010 3235);
PAINT ORANGE (-4010 3235);
FORCEPROP 2 LASTPIN (-4000 3175) $PN AB83
J 2
(-4010 3185);
DISPLAY 0.617021 (-4010 3185);
PAINT ORANGE (-4010 3185);
FORCEPROP 2 LASTPIN (-4000 3125) $PN AB85
J 2
(-4010 3135);
DISPLAY 0.617021 (-4010 3135);
PAINT ORANGE (-4010 3135);
FORCEPROP 2 LASTPIN (-4000 3075) $PN AC18
J 2
(-4010 3085);
DISPLAY 0.617021 (-4010 3085);
PAINT ORANGE (-4010 3085);
FORCEPROP 2 LASTPIN (-4000 3025) $PN AC22
J 2
(-4010 3035);
DISPLAY 0.617021 (-4010 3035);
PAINT ORANGE (-4010 3035);
FORCEPROP 2 LASTPIN (-4000 2975) $PN AC26
J 2
(-4010 2985);
DISPLAY 0.617021 (-4010 2985);
PAINT ORANGE (-4010 2985);
FORCEPROP 2 LASTPIN (-4000 2925) $PN AC28
J 2
(-4010 2935);
DISPLAY 0.617021 (-4010 2935);
PAINT ORANGE (-4010 2935);
FORCEPROP 2 LASTPIN (-4000 2875) $PN AC32
J 2
(-4010 2885);
DISPLAY 0.617021 (-4010 2885);
PAINT ORANGE (-4010 2885);
FORCEPROP 2 LASTPIN (-4000 2825) $PN AC34
J 2
(-4010 2835);
DISPLAY 0.617021 (-4010 2835);
PAINT ORANGE (-4010 2835);
FORCEPROP 2 LASTPIN (-4000 2775) $PN AC38
J 2
(-4010 2785);
DISPLAY 0.617021 (-4010 2785);
PAINT ORANGE (-4010 2785);
FORCEPROP 2 LASTPIN (-4000 2725) $PN AC40
J 2
(-4010 2735);
DISPLAY 0.617021 (-4010 2735);
PAINT ORANGE (-4010 2735);
FORCEPROP 2 LASTPIN (-4000 2675) $PN AC64
J 2
(-4010 2685);
DISPLAY 0.617021 (-4010 2685);
PAINT ORANGE (-4010 2685);
FORCEPROP 2 LASTPIN (-4000 2625) $PN AC70
J 2
(-4010 2635);
DISPLAY 0.617021 (-4010 2635);
PAINT ORANGE (-4010 2635);
FORCEPROP 2 LASTPIN (-4000 2575) $PN AC72
J 2
(-4010 2585);
DISPLAY 0.617021 (-4010 2585);
PAINT ORANGE (-4010 2585);
FORCEPROP 2 LASTPIN (-4000 2525) $PN AC78
J 2
(-4010 2535);
DISPLAY 0.617021 (-4010 2535);
PAINT ORANGE (-4010 2535);
FORCEPROP 2 LASTPIN (-4000 2475) $PN AC84
J 2
(-4010 2485);
DISPLAY 0.617021 (-4010 2485);
PAINT ORANGE (-4010 2485);
FORCEPROP 2 LASTPIN (-4000 2425) $PN AC86
J 2
(-4010 2435);
DISPLAY 0.617021 (-4010 2435);
PAINT ORANGE (-4010 2435);
FORCEPROP 2 LASTPIN (-4000 2375) $PN AD3
J 2
(-4010 2385);
DISPLAY 0.617021 (-4010 2385);
PAINT ORANGE (-4010 2385);
FORCEPROP 2 LASTPIN (-4000 2325) $PN AD7
J 2
(-4010 2335);
DISPLAY 0.617021 (-4010 2335);
PAINT ORANGE (-4010 2335);
FORCEPROP 2 LASTPIN (-4000 2275) $PN AD9
J 2
(-4010 2285);
DISPLAY 0.617021 (-4010 2285);
PAINT ORANGE (-4010 2285);
FORCEPROP 2 LASTPIN (-4000 2225) $PN AD11
J 2
(-4010 2235);
DISPLAY 0.617021 (-4010 2235);
PAINT ORANGE (-4010 2235);
FORCEPROP 2 LASTPIN (-4000 2175) $PN AD13
J 2
(-4010 2185);
DISPLAY 0.617021 (-4010 2185);
PAINT ORANGE (-4010 2185);
FORCEPROP 2 LASTPIN (-4000 2125) $PN AD15
J 2
(-4010 2135);
DISPLAY 0.617021 (-4010 2135);
PAINT ORANGE (-4010 2135);
FORCEPROP 2 LASTPIN (-4000 2075) $PN AD19
J 2
(-4010 2085);
DISPLAY 0.617021 (-4010 2085);
PAINT ORANGE (-4010 2085);
FORCEPROP 2 LASTPIN (-4000 2025) $PN AD21
J 2
(-4010 2035);
DISPLAY 0.617021 (-4010 2035);
PAINT ORANGE (-4010 2035);
FORCEPROP 2 LASTPIN (-4000 1975) $PN AD27
J 2
(-4010 1985);
DISPLAY 0.617021 (-4010 1985);
PAINT ORANGE (-4010 1985);
FORCEPROP 2 LASTPIN (-4000 1925) $PN AD33
J 2
(-4010 1935);
DISPLAY 0.617021 (-4010 1935);
PAINT ORANGE (-4010 1935);
FORCEPROP 2 LASTPIN (-4000 1875) $PN AD39
J 2
(-4010 1885);
DISPLAY 0.617021 (-4010 1885);
PAINT ORANGE (-4010 1885);
FORCEPROP 2 LASTPIN (-4000 1825) $PN AD43
J 2
(-4010 1835);
DISPLAY 0.617021 (-4010 1835);
PAINT ORANGE (-4010 1835);
FORCEPROP 2 LASTPIN (-4000 1775) $PN AD71
J 2
(-4010 1785);
DISPLAY 0.617021 (-4010 1785);
PAINT ORANGE (-4010 1785);
FORCEPROP 2 LASTPIN (-4000 1725) $PN AD73
J 2
(-4010 1735);
DISPLAY 0.617021 (-4010 1735);
PAINT ORANGE (-4010 1735);
FORCEPROP 2 LASTPIN (-4000 1675) $PN AD75
J 2
(-4010 1685);
DISPLAY 0.617021 (-4010 1685);
PAINT ORANGE (-4010 1685);
FORCEPROP 2 LASTPIN (-4000 1625) $PN AD81
J 2
(-4010 1635);
DISPLAY 0.617021 (-4010 1635);
PAINT ORANGE (-4010 1635);
FORCEPROP 2 LASTPIN (-4000 1575) $PN AD83
J 2
(-4010 1585);
DISPLAY 0.617021 (-4010 1585);
PAINT ORANGE (-4010 1585);
FORCEPROP 2 LASTPIN (-4000 1525) $PN AD85
J 2
(-4010 1535);
DISPLAY 0.617021 (-4010 1535);
PAINT ORANGE (-4010 1535);
FORCEPROP 2 LASTPIN (-4000 1475) $PN AE4
J 2
(-4010 1485);
DISPLAY 0.617021 (-4010 1485);
PAINT ORANGE (-4010 1485);
FORCEPROP 2 LASTPIN (-4000 1425) $PN AE8
J 2
(-4010 1435);
DISPLAY 0.617021 (-4010 1435);
PAINT ORANGE (-4010 1435);
FORCEPROP 2 LASTPIN (-4000 1375) $PN AC54
J 2
(-4010 1385);
DISPLAY 0.617021 (-4010 1385);
PAINT ORANGE (-4010 1385);
FORCEPROP 2 LASTPIN (-4000 1325) $PN AE16
J 2
(-4010 1335);
DISPLAY 0.617021 (-4010 1335);
PAINT ORANGE (-4010 1335);
FORCEPROP 2 LASTPIN (-4000 1275) $PN AE38
J 2
(-4010 1285);
DISPLAY 0.617021 (-4010 1285);
PAINT ORANGE (-4010 1285);
FORCEPROP 2 LASTPIN (-4000 1225) $PN AE40
J 2
(-4010 1235);
DISPLAY 0.617021 (-4010 1235);
PAINT ORANGE (-4010 1235);
FORCEPROP 2 LASTPIN (-4000 1175) $PN AE42
J 2
(-4010 1185);
DISPLAY 0.617021 (-4010 1185);
PAINT ORANGE (-4010 1185);
FORCEPROP 2 LASTPIN (-4000 1125) $PN AE64
J 2
(-4010 1135);
DISPLAY 0.617021 (-4010 1135);
PAINT ORANGE (-4010 1135);
FORCEPROP 2 LASTPIN (-4000 1075) $PN AE66
J 2
(-4010 1085);
DISPLAY 0.617021 (-4010 1085);
PAINT ORANGE (-4010 1085);
FORCEPROP 2 LASTPIN (-4000 1025) $PN AE68
J 2
(-4010 1035);
DISPLAY 0.617021 (-4010 1035);
PAINT ORANGE (-4010 1035);
FORCEPROP 2 LASTPIN (-4000 975) $PN AE70
J 2
(-4010 985);
DISPLAY 0.617021 (-4010 985);
PAINT ORANGE (-4010 985);
FORCEPROP 2 LASTPIN (-4000 925) $PN AE78
J 2
(-4010 935);
DISPLAY 0.617021 (-4010 935);
PAINT ORANGE (-4010 935);
FORCEPROP 2 LASTPIN (-4000 875) $PN AF1
J 2
(-4010 885);
DISPLAY 0.617021 (-4010 885);
PAINT ORANGE (-4010 885);
FORCEPROP 2 LASTPIN (-4000 825) $PN AC52
J 2
(-4010 835);
DISPLAY 0.617021 (-4010 835);
PAINT ORANGE (-4010 835);
FORCEPROP 2 LASTPIN (-4000 775) $PN AF9
J 2
(-4010 785);
DISPLAY 0.617021 (-4010 785);
PAINT ORANGE (-4010 785);
FORCEPROP 2 LASTPIN (-4000 725) $PN AF21
J 2
(-4010 735);
DISPLAY 0.617021 (-4010 735);
PAINT ORANGE (-4010 735);
FORCEPROP 2 LASTPIN (-4000 675) $PN AF23
J 2
(-4010 685);
DISPLAY 0.617021 (-4010 685);
PAINT ORANGE (-4010 685);
FORCEPROP 2 LASTPIN (-4000 625) $PN AF25
J 2
(-4010 635);
DISPLAY 0.617021 (-4010 635);
PAINT ORANGE (-4010 635);
FORCEPROP 2 LASTPIN (-2800 4575) $PN AF27
J 0
(-2790 4585);
DISPLAY 0.617021 (-2790 4585);
PAINT ORANGE (-2790 4585);
FORCEPROP 2 LASTPIN (-2800 4475) $PN AF31
J 0
(-2790 4485);
DISPLAY 0.617021 (-2790 4485);
PAINT ORANGE (-2790 4485);
FORCEPROP 2 LASTPIN (-2800 4425) $PN AF33
J 0
(-2790 4435);
DISPLAY 0.617021 (-2790 4435);
PAINT ORANGE (-2790 4435);
FORCEPROP 2 LASTPIN (-2800 4375) $PN AF37
J 0
(-2790 4385);
DISPLAY 0.617021 (-2790 4385);
PAINT ORANGE (-2790 4385);
FORCEPROP 2 LASTPIN (-2800 4325) $PN AF39
J 0
(-2790 4335);
DISPLAY 0.617021 (-2790 4335);
PAINT ORANGE (-2790 4335);
FORCEPROP 2 LASTPIN (-2800 4275) $PN AF41
J 0
(-2790 4285);
DISPLAY 0.617021 (-2790 4285);
PAINT ORANGE (-2790 4285);
FORCEPROP 2 LASTPIN (-2800 4225) $PN AF73
J 0
(-2790 4235);
DISPLAY 0.617021 (-2790 4235);
PAINT ORANGE (-2790 4235);
FORCEPROP 2 LASTPIN (-2800 4175) $PN AF77
J 0
(-2790 4185);
DISPLAY 0.617021 (-2790 4185);
PAINT ORANGE (-2790 4185);
FORCEPROP 2 LASTPIN (-2800 4125) $PN AF83
J 0
(-2790 4135);
DISPLAY 0.617021 (-2790 4135);
PAINT ORANGE (-2790 4135);
FORCEPROP 2 LASTPIN (-2800 4075) $PN AF85
J 0
(-2790 4085);
DISPLAY 0.617021 (-2790 4085);
PAINT ORANGE (-2790 4085);
FORCEPROP 2 LASTPIN (-2800 4025) $PN AG12
J 0
(-2790 4035);
DISPLAY 0.617021 (-2790 4035);
PAINT ORANGE (-2790 4035);
FORCEPROP 2 LASTPIN (-2800 3975) $PN AG14
J 0
(-2790 3985);
DISPLAY 0.617021 (-2790 3985);
PAINT ORANGE (-2790 3985);
FORCEPROP 2 LASTPIN (-2800 3925) $PN AG18
J 0
(-2790 3935);
DISPLAY 0.617021 (-2790 3935);
PAINT ORANGE (-2790 3935);
FORCEPROP 2 LASTPIN (-2800 3875) $PN AG36
J 0
(-2790 3885);
DISPLAY 0.617021 (-2790 3885);
PAINT ORANGE (-2790 3885);
FORCEPROP 2 LASTPIN (-2800 3825) $PN AG64
J 0
(-2790 3835);
DISPLAY 0.617021 (-2790 3835);
PAINT ORANGE (-2790 3835);
FORCEPROP 2 LASTPIN (-2800 3775) $PN AG70
J 0
(-2790 3785);
DISPLAY 0.617021 (-2790 3785);
PAINT ORANGE (-2790 3785);
FORCEPROP 2 LASTPIN (-2800 3725) $PN AG74
J 0
(-2790 3735);
DISPLAY 0.617021 (-2790 3735);
PAINT ORANGE (-2790 3735);
FORCEPROP 2 LASTPIN (-2800 3675) $PN AG76
J 0
(-2790 3685);
DISPLAY 0.617021 (-2790 3685);
PAINT ORANGE (-2790 3685);
FORCEPROP 2 LASTPIN (-2800 3575) $PN AG80
J 0
(-2790 3585);
DISPLAY 0.617021 (-2790 3585);
PAINT ORANGE (-2790 3585);
FORCEPROP 2 LASTPIN (-2800 3525) $PN AH1
J 0
(-2790 3535);
DISPLAY 0.617021 (-2790 3535);
PAINT ORANGE (-2790 3535);
FORCEPROP 2 LASTPIN (-2800 3475) $PN AH5
J 0
(-2790 3485);
DISPLAY 0.617021 (-2790 3485);
PAINT ORANGE (-2790 3485);
FORCEPROP 2 LASTPIN (-2800 3425) $PN AH21
J 0
(-2790 3435);
DISPLAY 0.617021 (-2790 3435);
PAINT ORANGE (-2790 3435);
FORCEPROP 2 LASTPIN (-2800 3375) $PN AH27
J 0
(-2790 3385);
DISPLAY 0.617021 (-2790 3385);
PAINT ORANGE (-2790 3385);
FORCEPROP 2 LASTPIN (-2800 3325) $PN AH33
J 0
(-2790 3335);
DISPLAY 0.617021 (-2790 3335);
PAINT ORANGE (-2790 3335);
FORCEPROP 2 LASTPIN (-2800 3275) $PN AH35
J 0
(-2790 3285);
DISPLAY 0.617021 (-2790 3285);
PAINT ORANGE (-2790 3285);
FORCEPROP 2 LASTPIN (-2800 3225) $PN AH45
J 0
(-2790 3235);
DISPLAY 0.617021 (-2790 3235);
PAINT ORANGE (-2790 3235);
FORCEPROP 2 LASTPIN (-2800 3175) $PN AH47
J 0
(-2790 3185);
DISPLAY 0.617021 (-2790 3185);
PAINT ORANGE (-2790 3185);
FORCEPROP 2 LASTPIN (-2800 3125) $PN AH49
J 0
(-2790 3135);
DISPLAY 0.617021 (-2790 3135);
PAINT ORANGE (-2790 3135);
FORCEPROP 2 LASTPIN (-2800 3075) $PN AH51
J 0
(-2790 3085);
DISPLAY 0.617021 (-2790 3085);
PAINT ORANGE (-2790 3085);
FORCEPROP 2 LASTPIN (-2800 3025) $PN AH53
J 0
(-2790 3035);
DISPLAY 0.617021 (-2790 3035);
PAINT ORANGE (-2790 3035);
FORCEPROP 2 LASTPIN (-2800 2975) $PN AH59
J 0
(-2790 2985);
DISPLAY 0.617021 (-2790 2985);
PAINT ORANGE (-2790 2985);
FORCEPROP 2 LASTPIN (-2800 2925) $PN AH61
J 0
(-2790 2935);
DISPLAY 0.617021 (-2790 2935);
PAINT ORANGE (-2790 2935);
FORCEPROP 2 LASTPIN (-2800 2875) $PN AH65
J 0
(-2790 2885);
DISPLAY 0.617021 (-2790 2885);
PAINT ORANGE (-2790 2885);
FORCEPROP 2 LASTPIN (-2800 2825) $PN AH69
J 0
(-2790 2835);
DISPLAY 0.617021 (-2790 2835);
PAINT ORANGE (-2790 2835);
FORCEPROP 2 LASTPIN (-2800 2775) $PN AH75
J 0
(-2790 2785);
DISPLAY 0.617021 (-2790 2785);
PAINT ORANGE (-2790 2785);
FORCEPROP 2 LASTPIN (-2800 2725) $PN AH77
J 0
(-2790 2735);
DISPLAY 0.617021 (-2790 2735);
PAINT ORANGE (-2790 2735);
FORCEPROP 2 LASTPIN (-2800 2675) $PN AH83
J 0
(-2790 2685);
DISPLAY 0.617021 (-2790 2685);
PAINT ORANGE (-2790 2685);
FORCEPROP 2 LASTPIN (-2800 2625) $PN AJ8
J 0
(-2790 2635);
DISPLAY 0.617021 (-2790 2635);
PAINT ORANGE (-2790 2635);
FORCEPROP 2 LASTPIN (-2800 2525) $PN AJ26
J 0
(-2790 2535);
DISPLAY 0.617021 (-2790 2535);
PAINT ORANGE (-2790 2535);
FORCEPROP 2 LASTPIN (-2800 2475) $PN AJ28
J 0
(-2790 2485);
DISPLAY 0.617021 (-2790 2485);
PAINT ORANGE (-2790 2485);
FORCEPROP 2 LASTPIN (-2800 2425) $PN AJ32
J 0
(-2790 2435);
DISPLAY 0.617021 (-2790 2435);
PAINT ORANGE (-2790 2435);
FORCEPROP 2 LASTPIN (-2800 2375) $PN AJ34
J 0
(-2790 2385);
DISPLAY 0.617021 (-2790 2385);
PAINT ORANGE (-2790 2385);
FORCEPROP 2 LASTPIN (-2800 2325) $PN AJ46
J 0
(-2790 2335);
DISPLAY 0.617021 (-2790 2335);
PAINT ORANGE (-2790 2335);
FORCEPROP 2 LASTPIN (-2800 2275) $PN AJ48
J 0
(-2790 2285);
DISPLAY 0.617021 (-2790 2285);
PAINT ORANGE (-2790 2285);
FORCEPROP 2 LASTPIN (-2800 2225) $PN AJ50
J 0
(-2790 2235);
DISPLAY 0.617021 (-2790 2235);
PAINT ORANGE (-2790 2235);
FORCEPROP 2 LASTPIN (-2800 2175) $PN AJ52
J 0
(-2790 2185);
DISPLAY 0.617021 (-2790 2185);
PAINT ORANGE (-2790 2185);
FORCEPROP 2 LASTPIN (-2800 2125) $PN AJ54
J 0
(-2790 2135);
DISPLAY 0.617021 (-2790 2135);
PAINT ORANGE (-2790 2135);
FORCEPROP 2 LASTPIN (-2800 2075) $PN AJ66
J 0
(-2790 2085);
DISPLAY 0.617021 (-2790 2085);
PAINT ORANGE (-2790 2085);
FORCEPROP 2 LASTPIN (-2800 2025) $PN AJ68
J 0
(-2790 2035);
DISPLAY 0.617021 (-2790 2035);
PAINT ORANGE (-2790 2035);
FORCEPROP 2 LASTPIN (-2800 1975) $PN AJ74
J 0
(-2790 1985);
DISPLAY 0.617021 (-2790 1985);
PAINT ORANGE (-2790 1985);
FORCEPROP 2 LASTPIN (-2800 1925) $PN AJ78
J 0
(-2790 1935);
DISPLAY 0.617021 (-2790 1935);
PAINT ORANGE (-2790 1935);
FORCEPROP 2 LASTPIN (-2800 1875) $PN AJ82
J 0
(-2790 1885);
DISPLAY 0.617021 (-2790 1885);
PAINT ORANGE (-2790 1885);
FORCEPROP 2 LASTPIN (-2800 1825) $PN AJ86
J 0
(-2790 1835);
DISPLAY 0.617021 (-2790 1835);
PAINT ORANGE (-2790 1835);
FORCEPROP 2 LASTPIN (-2800 1775) $PN AK9
J 0
(-2790 1785);
DISPLAY 0.617021 (-2790 1785);
PAINT ORANGE (-2790 1785);
FORCEPROP 2 LASTPIN (-2800 1725) $PN AK13
J 0
(-2790 1735);
DISPLAY 0.617021 (-2790 1735);
PAINT ORANGE (-2790 1735);
FORCEPROP 2 LASTPIN (-2800 1675) $PN AK19
J 0
(-2790 1685);
DISPLAY 0.617021 (-2790 1685);
PAINT ORANGE (-2790 1685);
FORCEPROP 2 LASTPIN (-2800 1625) $PN AK23
J 0
(-2790 1635);
DISPLAY 0.617021 (-2790 1635);
PAINT ORANGE (-2790 1635);
FORCEPROP 2 LASTPIN (-2800 1575) $PN AK25
J 0
(-2790 1585);
DISPLAY 0.617021 (-2790 1585);
PAINT ORANGE (-2790 1585);
FORCEPROP 2 LASTPIN (-2800 1525) $PN AK29
J 0
(-2790 1535);
DISPLAY 0.617021 (-2790 1535);
PAINT ORANGE (-2790 1535);
FORCEPROP 2 LASTPIN (-2800 1475) $PN AK31
J 0
(-2790 1485);
DISPLAY 0.617021 (-2790 1485);
PAINT ORANGE (-2790 1485);
FORCEPROP 2 LASTPIN (-2800 1425) $PN AK33
J 0
(-2790 1435);
DISPLAY 0.617021 (-2790 1435);
PAINT ORANGE (-2790 1435);
FORCEPROP 2 LASTPIN (-2800 1375) $PN AK55
J 0
(-2790 1385);
DISPLAY 0.617021 (-2790 1385);
PAINT ORANGE (-2790 1385);
FORCEPROP 2 LASTPIN (-2800 1325) $PN AK65
J 0
(-2790 1335);
DISPLAY 0.617021 (-2790 1335);
PAINT ORANGE (-2790 1335);
FORCEPROP 2 LASTPIN (-2800 1275) $PN AK67
J 0
(-2790 1285);
DISPLAY 0.617021 (-2790 1285);
PAINT ORANGE (-2790 1285);
FORCEPROP 2 LASTPIN (-2800 1225) $PN AK73
J 0
(-2790 1235);
DISPLAY 0.617021 (-2790 1235);
PAINT ORANGE (-2790 1235);
FORCEPROP 2 LASTPIN (-2800 1175) $PN AK79
J 0
(-2790 1185);
DISPLAY 0.617021 (-2790 1185);
PAINT ORANGE (-2790 1185);
FORCEPROP 2 LASTPIN (-2800 1125) $PN AK81
J 0
(-2790 1135);
DISPLAY 0.617021 (-2790 1135);
PAINT ORANGE (-2790 1135);
FORCEPROP 2 LASTPIN (-2800 1075) $PN AK83
J 0
(-2790 1085);
DISPLAY 0.617021 (-2790 1085);
PAINT ORANGE (-2790 1085);
FORCEPROP 2 LASTPIN (-2800 1025) $PN AK85
J 0
(-2790 1035);
DISPLAY 0.617021 (-2790 1035);
PAINT ORANGE (-2790 1035);
FORCEPROP 2 LASTPIN (-2800 975) $PN AL4
J 0
(-2790 985);
DISPLAY 0.617021 (-2790 985);
PAINT ORANGE (-2790 985);
FORCEPROP 2 LASTPIN (-2800 925) $PN AL10
J 0
(-2790 935);
DISPLAY 0.617021 (-2790 935);
PAINT ORANGE (-2790 935);
FORCEPROP 2 LASTPIN (-2800 875) $PN AL24
J 0
(-2790 885);
DISPLAY 0.617021 (-2790 885);
PAINT ORANGE (-2790 885);
FORCEPROP 2 LASTPIN (-2800 825) $PN AL30
J 0
(-2790 835);
DISPLAY 0.617021 (-2790 835);
PAINT ORANGE (-2790 835);
FORCEPROP 2 LASTPIN (-2800 775) $PN AL32
J 0
(-2790 785);
DISPLAY 0.617021 (-2790 785);
PAINT ORANGE (-2790 785);
FORCEPROP 2 LASTPIN (-2800 725) $PN AL56
J 0
(-2790 735);
DISPLAY 0.617021 (-2790 735);
PAINT ORANGE (-2790 735);
FORCEPROP 2 LASTPIN (-2800 675) $PN AL64
J 0
(-2790 685);
DISPLAY 0.617021 (-2790 685);
PAINT ORANGE (-2790 685);
FORCEPROP 2 LASTPIN (-2800 625) $PN AL68
J 0
(-2790 635);
DISPLAY 0.617021 (-2790 635);
PAINT ORANGE (-2790 635);
FORCEPROP 2 LASTPIN (-2800 2575) $PN AJ22
J 0
(-2790 2585);
DISPLAY 0.617021 (-2790 2585);
PAINT ORANGE (-2790 2585);
FORCEPROP 2 LASTPIN (-2800 3625) $PN AG78
J 0
(-2790 3635);
DISPLAY 0.617021 (-2790 3635);
PAINT ORANGE (-2790 3635);
FORCEPROP 2 LASTPIN (-2800 4525) $PN AF29
J 0
(-2790 4535);
DISPLAY 0.617021 (-2790 4535);
PAINT ORANGE (-2790 4535);
FORCEPROP 1 LAST PACK_TYPE BGA1
J 0
(-3950 4875);
PAINT SKYBLUE (-3950 4875);
DISPLAY INVISIBLE (-3950 4875);
FORCEPROP 2 LAST SEC_TYPE BGA1
J 0
(-3950 4875);
DISPLAY 1.021277 (-3950 4875);
PAINT ORANGE (-3950 4875);
DISPLAY INVISIBLE (-3950 4875);
FORCEPROP 2 LAST CDS_LIB chpset_lib
J 0
(-3400 2575);
PAINT ORANGE (-3400 2575);
DISPLAY INVISIBLE (-3400 2575);
FORCEPROP 2 LAST SEC 25
J 0
(-3950 4875);
DISPLAY 0.680851 (-3950 4875);
PAINT MONO (-3950 4875);
DISPLAY INVISIBLE (-3950 4875);
FORCEPROP 2 LAST CDS_LOCATION U5D1
J 0
(-3950 4825);
DISPLAY 0.617021 (-3950 4825);
PAINT AQUA (-3950 4825);
DISPLAY INVISIBLE (-3950 4825);
FORCEPROP 1 LAST PATH I22
J 0
(-3400 4775);
PAINT GREEN (-3400 4775);
DISPLAY INVISIBLE (-3400 4775);
FORCEPROP 0 LAST ROOM CPU0
J 0
(-3950 4925);
DISPLAY 1.021277 (-3950 4925);
PAINT ORANGE (-3950 4925);
DISPLAY INVISIBLE (-3950 4925);
FORCEADD SKX_EXT_B..26
(-1550 2575);
FORCEPROP 2 LASTPIN (-950 975) $PN BF69
J 0
(-940 985);
DISPLAY 0.617021 (-940 985);
PAINT ORANGE (-940 985);
FORCEPROP 2 LASTPIN (-950 825) $PN BG8
J 0
(-940 835);
DISPLAY 0.617021 (-940 835);
PAINT ORANGE (-940 835);
FORCEPROP 1 LAST LOCATION U5D1
J 0
(-2100 4825);
DISPLAY 0.617021 (-2100 4825);
PAINT AQUA (-2100 4825);
FORCEPROP 1 LAST PART_NUMBER TBD
J 0
(-2100 425);
DISPLAY 0.617021 (-2100 425);
PAINT BLUE (-2100 425);
FORCEPROP 1 LAST MATERIAL IC
J 0
(-2100 4775);
DISPLAY 0.617021 (-2100 4775);
PAINT SKYBLUE (-2100 4775);
FORCEPROP 2 LASTPIN (-2150 4575) $PN AL76
J 2
(-2160 4585);
DISPLAY 0.617021 (-2160 4585);
PAINT ORANGE (-2160 4585);
FORCEPROP 2 LASTPIN (-2150 4525) $PN AL78
J 2
(-2160 4535);
DISPLAY 0.617021 (-2160 4535);
PAINT ORANGE (-2160 4535);
FORCEPROP 2 LASTPIN (-2150 4475) $PN AL80
J 2
(-2160 4485);
DISPLAY 0.617021 (-2160 4485);
PAINT ORANGE (-2160 4485);
FORCEPROP 2 LASTPIN (-2150 4425) $PN AL82
J 2
(-2160 4435);
DISPLAY 0.617021 (-2160 4435);
PAINT ORANGE (-2160 4435);
FORCEPROP 2 LASTPIN (-2150 4375) $PN AL86
J 2
(-2160 4385);
DISPLAY 0.617021 (-2160 4385);
PAINT ORANGE (-2160 4385);
FORCEPROP 2 LASTPIN (-2150 4325) $PN AM1
J 2
(-2160 4335);
DISPLAY 0.617021 (-2160 4335);
PAINT ORANGE (-2160 4335);
FORCEPROP 2 LASTPIN (-2150 4275) $PN AC50
J 2
(-2160 4285);
DISPLAY 0.617021 (-2160 4285);
PAINT ORANGE (-2160 4285);
FORCEPROP 2 LASTPIN (-2150 4225) $PN AM31
J 2
(-2160 4235);
DISPLAY 0.617021 (-2160 4235);
PAINT ORANGE (-2160 4235);
FORCEPROP 2 LASTPIN (-2150 4175) $PN AM57
J 2
(-2160 4185);
DISPLAY 0.617021 (-2160 4185);
PAINT ORANGE (-2160 4185);
FORCEPROP 2 LASTPIN (-2150 4125) $PN AM63
J 2
(-2160 4135);
DISPLAY 0.617021 (-2160 4135);
PAINT ORANGE (-2160 4135);
FORCEPROP 2 LASTPIN (-2150 4075) $PN AM69
J 2
(-2160 4085);
DISPLAY 0.617021 (-2160 4085);
PAINT ORANGE (-2160 4085);
FORCEPROP 2 LASTPIN (-2150 4025) $PN AM73
J 2
(-2160 4035);
DISPLAY 0.617021 (-2160 4035);
PAINT ORANGE (-2160 4035);
FORCEPROP 2 LASTPIN (-2150 3975) $PN AM79
J 2
(-2160 3985);
DISPLAY 0.617021 (-2160 3985);
PAINT ORANGE (-2160 3985);
FORCEPROP 2 LASTPIN (-2150 3925) $PN AM83
J 2
(-2160 3935);
DISPLAY 0.617021 (-2160 3935);
PAINT ORANGE (-2160 3935);
FORCEPROP 2 LASTPIN (-2150 3875) $PN AN2
J 2
(-2160 3885);
DISPLAY 0.617021 (-2160 3885);
PAINT ORANGE (-2160 3885);
FORCEPROP 2 LASTPIN (-2150 3825) $PN AN6
J 2
(-2160 3835);
DISPLAY 0.617021 (-2160 3835);
PAINT ORANGE (-2160 3835);
FORCEPROP 2 LASTPIN (-2150 3775) $PN AN28
J 2
(-2160 3785);
DISPLAY 0.617021 (-2160 3785);
PAINT ORANGE (-2160 3785);
FORCEPROP 2 LASTPIN (-2150 3725) $PN AN58
J 2
(-2160 3735);
DISPLAY 0.617021 (-2160 3735);
PAINT ORANGE (-2160 3735);
FORCEPROP 2 LASTPIN (-2150 3675) $PN AN78
J 2
(-2160 3685);
DISPLAY 0.617021 (-2160 3685);
PAINT ORANGE (-2160 3685);
FORCEPROP 2 LASTPIN (-2150 3625) $PN AP5
J 2
(-2160 3635);
DISPLAY 0.617021 (-2160 3635);
PAINT ORANGE (-2160 3635);
FORCEPROP 2 LASTPIN (-2150 3575) $PN AP9
J 2
(-2160 3585);
DISPLAY 0.617021 (-2160 3585);
PAINT ORANGE (-2160 3585);
FORCEPROP 2 LASTPIN (-2150 3525) $PN AP13
J 2
(-2160 3535);
DISPLAY 0.617021 (-2160 3535);
PAINT ORANGE (-2160 3535);
FORCEPROP 2 LASTPIN (-2150 3475) $PN AP19
J 2
(-2160 3485);
DISPLAY 0.617021 (-2160 3485);
PAINT ORANGE (-2160 3485);
FORCEPROP 2 LASTPIN (-2150 3425) $PN AP31
J 2
(-2160 3435);
DISPLAY 0.617021 (-2160 3435);
PAINT ORANGE (-2160 3435);
FORCEPROP 2 LASTPIN (-2150 3375) $PN AP59
J 2
(-2160 3385);
DISPLAY 0.617021 (-2160 3385);
PAINT ORANGE (-2160 3385);
FORCEPROP 2 LASTPIN (-2150 3325) $PN AP63
J 2
(-2160 3335);
DISPLAY 0.617021 (-2160 3335);
PAINT ORANGE (-2160 3335);
FORCEPROP 2 LASTPIN (-2150 3275) $PN AP65
J 2
(-2160 3285);
DISPLAY 0.617021 (-2160 3285);
PAINT ORANGE (-2160 3285);
FORCEPROP 2 LASTPIN (-2150 3225) $PN AP67
J 2
(-2160 3235);
DISPLAY 0.617021 (-2160 3235);
PAINT ORANGE (-2160 3235);
FORCEPROP 2 LASTPIN (-2150 3175) $PN AP69
J 2
(-2160 3185);
DISPLAY 0.617021 (-2160 3185);
PAINT ORANGE (-2160 3185);
FORCEPROP 2 LASTPIN (-2150 3125) $PN AP73
J 2
(-2160 3135);
DISPLAY 0.617021 (-2160 3135);
PAINT ORANGE (-2160 3135);
FORCEPROP 2 LASTPIN (-2150 3075) $PN AP75
J 2
(-2160 3085);
DISPLAY 0.617021 (-2160 3085);
PAINT ORANGE (-2160 3085);
FORCEPROP 2 LASTPIN (-2150 3025) $PN AP81
J 2
(-2160 3035);
DISPLAY 0.617021 (-2160 3035);
PAINT ORANGE (-2160 3035);
FORCEPROP 2 LASTPIN (-2150 2975) $PN AP83
J 2
(-2160 2985);
DISPLAY 0.617021 (-2160 2985);
PAINT ORANGE (-2160 2985);
FORCEPROP 2 LASTPIN (-2150 2925) $PN AP85
J 2
(-2160 2935);
DISPLAY 0.617021 (-2160 2935);
PAINT ORANGE (-2160 2935);
FORCEPROP 2 LASTPIN (-2150 2875) $PN AR10
J 2
(-2160 2885);
DISPLAY 0.617021 (-2160 2885);
PAINT ORANGE (-2160 2885);
FORCEPROP 2 LASTPIN (-2150 2825) $PN AR24
J 2
(-2160 2835);
DISPLAY 0.617021 (-2160 2835);
PAINT ORANGE (-2160 2835);
FORCEPROP 2 LASTPIN (-2150 2775) $PN AR30
J 2
(-2160 2785);
DISPLAY 0.617021 (-2160 2785);
PAINT ORANGE (-2160 2785);
FORCEPROP 2 LASTPIN (-2150 2725) $PN AR60
J 2
(-2160 2735);
DISPLAY 0.617021 (-2160 2735);
PAINT ORANGE (-2160 2735);
FORCEPROP 2 LASTPIN (-2150 2675) $PN AR72
J 2
(-2160 2685);
DISPLAY 0.617021 (-2160 2685);
PAINT ORANGE (-2160 2685);
FORCEPROP 2 LASTPIN (-2150 2625) $PN AR78
J 2
(-2160 2635);
DISPLAY 0.617021 (-2160 2635);
PAINT ORANGE (-2160 2635);
FORCEPROP 2 LASTPIN (-2150 2525) $PN P63
J 2
(-2160 2535);
DISPLAY 0.617021 (-2160 2535);
PAINT ORANGE (-2160 2535);
FORCEPROP 2 LASTPIN (-2150 2475) $PN AT15
J 2
(-2160 2485);
DISPLAY 0.617021 (-2160 2485);
PAINT ORANGE (-2160 2485);
FORCEPROP 2 LASTPIN (-2150 2425) $PN AT17
J 2
(-2160 2435);
DISPLAY 0.617021 (-2160 2435);
PAINT ORANGE (-2160 2435);
FORCEPROP 2 LASTPIN (-2150 2375) $PN AT21
J 2
(-2160 2385);
DISPLAY 0.617021 (-2160 2385);
PAINT ORANGE (-2160 2385);
FORCEPROP 2 LASTPIN (-2150 2325) $PN AT27
J 2
(-2160 2335);
DISPLAY 0.617021 (-2160 2335);
PAINT ORANGE (-2160 2335);
FORCEPROP 2 LASTPIN (-2150 2275) $PN AT61
J 2
(-2160 2285);
DISPLAY 0.617021 (-2160 2285);
PAINT ORANGE (-2160 2285);
FORCEPROP 2 LASTPIN (-2150 2175) $PN AT69
J 2
(-2160 2185);
DISPLAY 0.617021 (-2160 2185);
PAINT ORANGE (-2160 2185);
FORCEPROP 2 LASTPIN (-2150 2125) $PN AT73
J 2
(-2160 2135);
DISPLAY 0.617021 (-2160 2135);
PAINT ORANGE (-2160 2135);
FORCEPROP 2 LASTPIN (-2150 2075) $PN AT77
J 2
(-2160 2085);
DISPLAY 0.617021 (-2160 2085);
PAINT ORANGE (-2160 2085);
FORCEPROP 2 LASTPIN (-2150 2025) $PN AT83
J 2
(-2160 2035);
DISPLAY 0.617021 (-2160 2035);
PAINT ORANGE (-2160 2035);
FORCEPROP 2 LASTPIN (-2150 1975) $PN AT85
J 2
(-2160 1985);
DISPLAY 0.617021 (-2160 1985);
PAINT ORANGE (-2160 1985);
FORCEPROP 2 LASTPIN (-2150 1925) $PN AU2
J 2
(-2160 1935);
DISPLAY 0.617021 (-2160 1935);
PAINT ORANGE (-2160 1935);
FORCEPROP 2 LASTPIN (-2150 1875) $PN AU6
J 2
(-2160 1885);
DISPLAY 0.617021 (-2160 1885);
PAINT ORANGE (-2160 1885);
FORCEPROP 2 LASTPIN (-2150 1825) $PN AU26
J 2
(-2160 1835);
DISPLAY 0.617021 (-2160 1835);
PAINT ORANGE (-2160 1835);
FORCEPROP 2 LASTPIN (-2150 1775) $PN AU28
J 2
(-2160 1785);
DISPLAY 0.617021 (-2160 1785);
PAINT ORANGE (-2160 1785);
FORCEPROP 2 LASTPIN (-2150 1725) $PN AU62
J 2
(-2160 1735);
DISPLAY 0.617021 (-2160 1735);
PAINT ORANGE (-2160 1735);
FORCEPROP 2 LASTPIN (-2150 1675) $PN AU64
J 2
(-2160 1685);
DISPLAY 0.617021 (-2160 1685);
PAINT ORANGE (-2160 1685);
FORCEPROP 2 LASTPIN (-2150 1625) $PN AU68
J 2
(-2160 1635);
DISPLAY 0.617021 (-2160 1635);
PAINT ORANGE (-2160 1635);
FORCEPROP 2 LASTPIN (-2150 1575) $PN AU74
J 2
(-2160 1585);
DISPLAY 0.617021 (-2160 1585);
PAINT ORANGE (-2160 1585);
FORCEPROP 2 LASTPIN (-2150 1525) $PN AU76
J 2
(-2160 1535);
DISPLAY 0.617021 (-2160 1535);
PAINT ORANGE (-2160 1535);
FORCEPROP 2 LASTPIN (-2150 1475) $PN AU78
J 2
(-2160 1485);
DISPLAY 0.617021 (-2160 1485);
PAINT ORANGE (-2160 1485);
FORCEPROP 2 LASTPIN (-2150 1425) $PN AU80
J 2
(-2160 1435);
DISPLAY 0.617021 (-2160 1435);
PAINT ORANGE (-2160 1435);
FORCEPROP 2 LASTPIN (-2150 1375) $PN AU84
J 2
(-2160 1385);
DISPLAY 0.617021 (-2160 1385);
PAINT ORANGE (-2160 1385);
FORCEPROP 2 LASTPIN (-2150 1325) $PN AU86
J 2
(-2160 1335);
DISPLAY 0.617021 (-2160 1335);
PAINT ORANGE (-2160 1335);
FORCEPROP 2 LASTPIN (-2150 1275) $PN AV1
J 2
(-2160 1285);
DISPLAY 0.617021 (-2160 1285);
PAINT ORANGE (-2160 1285);
FORCEPROP 2 LASTPIN (-2150 1225) $PN AV3
J 2
(-2160 1235);
DISPLAY 0.617021 (-2160 1235);
PAINT ORANGE (-2160 1235);
FORCEPROP 2 LASTPIN (-2150 1175) $PN AV7
J 2
(-2160 1185);
DISPLAY 0.617021 (-2160 1185);
PAINT ORANGE (-2160 1185);
FORCEPROP 2 LASTPIN (-2150 1125) $PN AV11
J 2
(-2160 1135);
DISPLAY 0.617021 (-2160 1135);
PAINT ORANGE (-2160 1135);
FORCEPROP 2 LASTPIN (-2150 1075) $PN AV13
J 2
(-2160 1085);
DISPLAY 0.617021 (-2160 1085);
PAINT ORANGE (-2160 1085);
FORCEPROP 2 LASTPIN (-2150 1025) $PN AV19
J 2
(-2160 1035);
DISPLAY 0.617021 (-2160 1035);
PAINT ORANGE (-2160 1035);
FORCEPROP 2 LASTPIN (-2150 975) $PN AV23
J 2
(-2160 985);
DISPLAY 0.617021 (-2160 985);
PAINT ORANGE (-2160 985);
FORCEPROP 2 LASTPIN (-2150 925) $PN AV25
J 2
(-2160 935);
DISPLAY 0.617021 (-2160 935);
PAINT ORANGE (-2160 935);
FORCEPROP 2 LASTPIN (-2150 875) $PN AV63
J 2
(-2160 885);
DISPLAY 0.617021 (-2160 885);
PAINT ORANGE (-2160 885);
FORCEPROP 2 LASTPIN (-2150 825) $PN AV65
J 2
(-2160 835);
DISPLAY 0.617021 (-2160 835);
PAINT ORANGE (-2160 835);
FORCEPROP 2 LASTPIN (-2150 775) $PN AV67
J 2
(-2160 785);
DISPLAY 0.617021 (-2160 785);
PAINT ORANGE (-2160 785);
FORCEPROP 2 LASTPIN (-2150 725) $PN AV75
J 2
(-2160 735);
DISPLAY 0.617021 (-2160 735);
PAINT ORANGE (-2160 735);
FORCEPROP 2 LASTPIN (-2150 675) $PN AV83
J 2
(-2160 685);
DISPLAY 0.617021 (-2160 685);
PAINT ORANGE (-2160 685);
FORCEPROP 2 LASTPIN (-2150 625) $PN AW2
J 2
(-2160 635);
DISPLAY 0.617021 (-2160 635);
PAINT ORANGE (-2160 635);
FORCEPROP 2 LASTPIN (-950 4575) $PN AW10
J 0
(-940 4585);
DISPLAY 0.617021 (-940 4585);
PAINT ORANGE (-940 4585);
FORCEPROP 2 LASTPIN (-950 4525) $PN AW62
J 0
(-940 4535);
DISPLAY 0.617021 (-940 4535);
PAINT ORANGE (-940 4535);
FORCEPROP 2 LASTPIN (-950 4475) $PN AW66
J 0
(-940 4485);
DISPLAY 0.617021 (-940 4485);
PAINT ORANGE (-940 4485);
FORCEPROP 2 LASTPIN (-950 4425) $PN AW68
J 0
(-940 4435);
DISPLAY 0.617021 (-940 4435);
PAINT ORANGE (-940 4435);
FORCEPROP 2 LASTPIN (-950 4375) $PN AW70
J 0
(-940 4385);
DISPLAY 0.617021 (-940 4385);
PAINT ORANGE (-940 4385);
FORCEPROP 2 LASTPIN (-950 4325) $PN AW72
J 0
(-940 4335);
DISPLAY 0.617021 (-940 4335);
PAINT ORANGE (-940 4335);
FORCEPROP 2 LASTPIN (-950 4275) $PN AW74
J 0
(-940 4285);
DISPLAY 0.617021 (-940 4285);
PAINT ORANGE (-940 4285);
FORCEPROP 2 LASTPIN (-950 4225) $PN AW78
J 0
(-940 4235);
DISPLAY 0.617021 (-940 4235);
PAINT ORANGE (-940 4235);
FORCEPROP 2 LASTPIN (-950 4175) $PN AW82
J 0
(-940 4185);
DISPLAY 0.617021 (-940 4185);
PAINT ORANGE (-940 4185);
FORCEPROP 2 LASTPIN (-950 4125) $PN AW84
J 0
(-940 4135);
DISPLAY 0.617021 (-940 4135);
PAINT ORANGE (-940 4135);
FORCEPROP 2 LASTPIN (-950 4075) $PN AY5
J 0
(-940 4085);
DISPLAY 0.617021 (-940 4085);
PAINT ORANGE (-940 4085);
FORCEPROP 2 LASTPIN (-950 4025) $PN AY15
J 0
(-940 4035);
DISPLAY 0.617021 (-940 4035);
PAINT ORANGE (-940 4035);
FORCEPROP 2 LASTPIN (-950 3975) $PN AY17
J 0
(-940 3985);
DISPLAY 0.617021 (-940 3985);
PAINT ORANGE (-940 3985);
FORCEPROP 2 LASTPIN (-950 3925) $PN AY21
J 0
(-940 3935);
DISPLAY 0.617021 (-940 3935);
PAINT ORANGE (-940 3935);
FORCEPROP 2 LASTPIN (-950 3875) $PN AY23
J 0
(-940 3885);
DISPLAY 0.617021 (-940 3885);
PAINT ORANGE (-940 3885);
FORCEPROP 2 LASTPIN (-950 3825) $PN AY25
J 0
(-940 3835);
DISPLAY 0.617021 (-940 3835);
PAINT ORANGE (-940 3835);
FORCEPROP 2 LASTPIN (-950 3775) $PN AY63
J 0
(-940 3785);
DISPLAY 0.617021 (-940 3785);
PAINT ORANGE (-940 3785);
FORCEPROP 2 LASTPIN (-950 3725) $PN AY79
J 0
(-940 3735);
DISPLAY 0.617021 (-940 3735);
PAINT ORANGE (-940 3735);
FORCEPROP 2 LASTPIN (-950 3675) $PN AY81
J 0
(-940 3685);
DISPLAY 0.617021 (-940 3685);
PAINT ORANGE (-940 3685);
FORCEPROP 2 LASTPIN (-950 3625) $PN BA2
J 0
(-940 3635);
DISPLAY 0.617021 (-940 3635);
PAINT ORANGE (-940 3635);
FORCEPROP 2 LASTPIN (-950 3575) $PN BA6
J 0
(-940 3585);
DISPLAY 0.617021 (-940 3585);
PAINT ORANGE (-940 3585);
FORCEPROP 2 LASTPIN (-950 3525) $PN BA12
J 0
(-940 3535);
DISPLAY 0.617021 (-940 3535);
PAINT ORANGE (-940 3535);
FORCEPROP 2 LASTPIN (-950 3475) $PN BA62
J 0
(-940 3485);
DISPLAY 0.617021 (-940 3485);
PAINT ORANGE (-940 3485);
FORCEPROP 2 LASTPIN (-950 3425) $PN BA68
J 0
(-940 3435);
DISPLAY 0.617021 (-940 3435);
PAINT ORANGE (-940 3435);
FORCEPROP 2 LASTPIN (-950 3375) $PN BA74
J 0
(-940 3385);
DISPLAY 0.617021 (-940 3385);
PAINT ORANGE (-940 3385);
FORCEPROP 2 LASTPIN (-950 3325) $PN BA80
J 0
(-940 3335);
DISPLAY 0.617021 (-940 3335);
PAINT ORANGE (-940 3335);
FORCEPROP 2 LASTPIN (-950 3275) $PN BA84
J 0
(-940 3285);
DISPLAY 0.617021 (-940 3285);
PAINT ORANGE (-940 3285);
FORCEPROP 2 LASTPIN (-950 3225) $PN BB19
J 0
(-940 3235);
DISPLAY 0.617021 (-940 3235);
PAINT ORANGE (-940 3235);
FORCEPROP 2 LASTPIN (-950 3175) $PN BB23
J 0
(-940 3185);
DISPLAY 0.617021 (-940 3185);
PAINT ORANGE (-940 3185);
FORCEPROP 2 LASTPIN (-950 3125) $PN BB63
J 0
(-940 3135);
DISPLAY 0.617021 (-940 3135);
PAINT ORANGE (-940 3135);
FORCEPROP 2 LASTPIN (-950 3075) $PN BB69
J 0
(-940 3085);
DISPLAY 0.617021 (-940 3085);
PAINT ORANGE (-940 3085);
FORCEPROP 2 LASTPIN (-950 3025) $PN BB73
J 0
(-940 3035);
DISPLAY 0.617021 (-940 3035);
PAINT ORANGE (-940 3035);
FORCEPROP 2 LASTPIN (-950 2975) $PN BB75
J 0
(-940 2985);
DISPLAY 0.617021 (-940 2985);
PAINT ORANGE (-940 2985);
FORCEPROP 2 LASTPIN (-950 2925) $PN BB77
J 0
(-940 2935);
DISPLAY 0.617021 (-940 2935);
PAINT ORANGE (-940 2935);
FORCEPROP 2 LASTPIN (-950 2875) $PN BB79
J 0
(-940 2885);
DISPLAY 0.617021 (-940 2885);
PAINT ORANGE (-940 2885);
FORCEPROP 2 LASTPIN (-950 2825) $PN BB81
J 0
(-940 2835);
DISPLAY 0.617021 (-940 2835);
PAINT ORANGE (-940 2835);
FORCEPROP 2 LASTPIN (-950 2775) $PN BB83
J 0
(-940 2785);
DISPLAY 0.617021 (-940 2785);
PAINT ORANGE (-940 2785);
FORCEPROP 2 LASTPIN (-950 2725) $PN BC4
J 0
(-940 2735);
DISPLAY 0.617021 (-940 2735);
PAINT ORANGE (-940 2735);
FORCEPROP 2 LASTPIN (-950 2675) $PN BC8
J 0
(-940 2685);
DISPLAY 0.617021 (-940 2685);
PAINT ORANGE (-940 2685);
FORCEPROP 2 LASTPIN (-950 2625) $PN BC12
J 0
(-940 2635);
DISPLAY 0.617021 (-940 2635);
PAINT ORANGE (-940 2635);
FORCEPROP 2 LASTPIN (-950 2575) $PN BC16
J 0
(-940 2585);
DISPLAY 0.617021 (-940 2585);
PAINT ORANGE (-940 2585);
FORCEPROP 2 LASTPIN (-950 2525) $PN BC70
J 0
(-940 2535);
DISPLAY 0.617021 (-940 2535);
PAINT ORANGE (-940 2535);
FORCEPROP 2 LASTPIN (-950 2475) $PN BC72
J 0
(-940 2485);
DISPLAY 0.617021 (-940 2485);
PAINT ORANGE (-940 2485);
FORCEPROP 2 LASTPIN (-950 2425) $PN BC74
J 0
(-940 2435);
DISPLAY 0.617021 (-940 2435);
PAINT ORANGE (-940 2435);
FORCEPROP 2 LASTPIN (-950 2375) $PN BC76
J 0
(-940 2385);
DISPLAY 0.617021 (-940 2385);
PAINT ORANGE (-940 2385);
FORCEPROP 2 LASTPIN (-950 2325) $PN BC78
J 0
(-940 2335);
DISPLAY 0.617021 (-940 2335);
PAINT ORANGE (-940 2335);
FORCEPROP 2 LASTPIN (-950 2275) $PN BC80
J 0
(-940 2285);
DISPLAY 0.617021 (-940 2285);
PAINT ORANGE (-940 2285);
FORCEPROP 2 LASTPIN (-950 2225) $PN BC82
J 0
(-940 2235);
DISPLAY 0.617021 (-940 2235);
PAINT ORANGE (-940 2235);
FORCEPROP 2 LASTPIN (-950 2175) $PN BD5
J 0
(-940 2185);
DISPLAY 0.617021 (-940 2185);
PAINT ORANGE (-940 2185);
FORCEPROP 2 LASTPIN (-950 2125) $PN BD11
J 0
(-940 2135);
DISPLAY 0.617021 (-940 2135);
PAINT ORANGE (-940 2135);
FORCEPROP 2 LASTPIN (-950 2075) $PN BD15
J 0
(-940 2085);
DISPLAY 0.617021 (-940 2085);
PAINT ORANGE (-940 2085);
FORCEPROP 2 LASTPIN (-950 2025) $PN BD21
J 0
(-940 2035);
DISPLAY 0.617021 (-940 2035);
PAINT ORANGE (-940 2035);
FORCEPROP 2 LASTPIN (-950 1975) $PN BD27
J 0
(-940 1985);
DISPLAY 0.617021 (-940 1985);
PAINT ORANGE (-940 1985);
FORCEPROP 2 LASTPIN (-950 1925) $PN BD63
J 0
(-940 1935);
DISPLAY 0.617021 (-940 1935);
PAINT ORANGE (-940 1935);
FORCEPROP 2 LASTPIN (-950 1875) $PN BD71
J 0
(-940 1885);
DISPLAY 0.617021 (-940 1885);
PAINT ORANGE (-940 1885);
FORCEPROP 2 LASTPIN (-950 1825) $PN BE4
J 0
(-940 1835);
DISPLAY 0.617021 (-940 1835);
PAINT ORANGE (-940 1835);
FORCEPROP 2 LASTPIN (-950 1775) $PN BE6
J 0
(-940 1785);
DISPLAY 0.617021 (-940 1785);
PAINT ORANGE (-940 1785);
FORCEPROP 2 LASTPIN (-950 1725) $PN BE8
J 0
(-940 1735);
DISPLAY 0.617021 (-940 1735);
PAINT ORANGE (-940 1735);
FORCEPROP 2 LASTPIN (-950 1675) $PN BE10
J 0
(-940 1685);
DISPLAY 0.617021 (-940 1685);
PAINT ORANGE (-940 1685);
FORCEPROP 2 LASTPIN (-950 1625) $PN BE26
J 0
(-940 1635);
DISPLAY 0.617021 (-940 1635);
PAINT ORANGE (-940 1635);
FORCEPROP 2 LASTPIN (-950 1575) $PN BE64
J 0
(-940 1585);
DISPLAY 0.617021 (-940 1585);
PAINT ORANGE (-940 1585);
FORCEPROP 2 LASTPIN (-950 1525) $PN BE66
J 0
(-940 1535);
DISPLAY 0.617021 (-940 1535);
PAINT ORANGE (-940 1535);
FORCEPROP 2 LASTPIN (-950 1475) $PN BE68
J 0
(-940 1485);
DISPLAY 0.617021 (-940 1485);
PAINT ORANGE (-940 1485);
FORCEPROP 2 LASTPIN (-950 1425) $PN BE70
J 0
(-940 1435);
DISPLAY 0.617021 (-940 1435);
PAINT ORANGE (-940 1435);
FORCEPROP 2 LASTPIN (-950 1375) $PN BF9
J 0
(-940 1385);
DISPLAY 0.617021 (-940 1385);
PAINT ORANGE (-940 1385);
FORCEPROP 2 LASTPIN (-950 1325) $PN BF15
J 0
(-940 1335);
DISPLAY 0.617021 (-940 1335);
PAINT ORANGE (-940 1335);
FORCEPROP 2 LASTPIN (-950 1275) $PN BF17
J 0
(-940 1285);
DISPLAY 0.617021 (-940 1285);
PAINT ORANGE (-940 1285);
FORCEPROP 2 LASTPIN (-950 1225) $PN BF19
J 0
(-940 1235);
DISPLAY 0.617021 (-940 1235);
PAINT ORANGE (-940 1235);
FORCEPROP 2 LASTPIN (-950 1175) $PN BF25
J 0
(-940 1185);
DISPLAY 0.617021 (-940 1185);
PAINT ORANGE (-940 1185);
FORCEPROP 2 LASTPIN (-950 1125) $PN BF63
J 0
(-940 1135);
DISPLAY 0.617021 (-940 1135);
PAINT ORANGE (-940 1135);
FORCEPROP 2 LASTPIN (-950 1075) $PN BF65
J 0
(-940 1085);
DISPLAY 0.617021 (-940 1085);
PAINT ORANGE (-940 1085);
FORCEPROP 2 LASTPIN (-950 1025) $PN BF67
J 0
(-940 1035);
DISPLAY 0.617021 (-940 1035);
PAINT ORANGE (-940 1035);
FORCEPROP 2 LASTPIN (-950 925) $PN BF71
J 0
(-940 935);
DISPLAY 0.617021 (-940 935);
PAINT ORANGE (-940 935);
FORCEPROP 2 LASTPIN (-950 875) $PN BG6
J 0
(-940 885);
DISPLAY 0.617021 (-940 885);
PAINT ORANGE (-940 885);
FORCEPROP 2 LASTPIN (-950 775) $PN BG10
J 0
(-940 785);
DISPLAY 0.617021 (-940 785);
PAINT ORANGE (-940 785);
FORCEPROP 2 LASTPIN (-950 725) $PN BG22
J 0
(-940 735);
DISPLAY 0.617021 (-940 735);
PAINT ORANGE (-940 735);
FORCEPROP 2 LASTPIN (-950 675) $PN BG24
J 0
(-940 685);
DISPLAY 0.617021 (-940 685);
PAINT ORANGE (-940 685);
FORCEPROP 2 LASTPIN (-950 625) $PN BG72
J 0
(-940 635);
DISPLAY 0.617021 (-940 635);
PAINT ORANGE (-940 635);
FORCEPROP 2 LASTPIN (-2150 2225) $PN AT63
J 2
(-2160 2235);
DISPLAY 0.617021 (-2160 2235);
PAINT ORANGE (-2160 2235);
FORCEPROP 2 LASTPIN (-2150 2575) $PN AC48
J 2
(-2160 2585);
DISPLAY 0.617021 (-2160 2585);
PAINT ORANGE (-2160 2585);
FORCEPROP 1 LAST PACK_TYPE BGA1
J 0
(-2100 4875);
PAINT SKYBLUE (-2100 4875);
DISPLAY INVISIBLE (-2100 4875);
FORCEPROP 2 LAST SEC_TYPE BGA1
J 0
(-2100 4875);
DISPLAY 1.021277 (-2100 4875);
PAINT ORANGE (-2100 4875);
DISPLAY INVISIBLE (-2100 4875);
FORCEPROP 2 LAST CDS_LIB chpset_lib
J 0
(-1550 2575);
PAINT ORANGE (-1550 2575);
DISPLAY INVISIBLE (-1550 2575);
FORCEPROP 2 LAST SEC 26
J 0
(-2100 4875);
DISPLAY 0.680851 (-2100 4875);
PAINT MONO (-2100 4875);
DISPLAY INVISIBLE (-2100 4875);
FORCEPROP 2 LAST CDS_LOCATION U5D1
J 0
(-2100 4825);
DISPLAY 0.617021 (-2100 4825);
PAINT AQUA (-2100 4825);
DISPLAY INVISIBLE (-2100 4825);
FORCEPROP 1 LAST PATH I23
J 0
(-1550 4775);
PAINT GREEN (-1550 4775);
DISPLAY INVISIBLE (-1550 4775);
FORCEPROP 0 LAST ROOM CPU0
J 0
(-2100 4925);
DISPLAY 1.021277 (-2100 4925);
PAINT ORANGE (-2100 4925);
DISPLAY INVISIBLE (-2100 4925);
FORCEADD GND..1
(-7800 450);
FORCEPROP 3 LASTPIN (-7800 500) SIG_NAME GND\g
J 0
(-7790 510);
DISPLAY 0.659574 (-7790 510);
PAINT MONO (-7790 510);
DISPLAY INVISIBLE (-7790 510);
FORCEPROP 1 LAST VOLTAGE 0.0V
J 0
(-7845 407);
DISPLAY 0.340426 (-7845 407);
PAINT SKYBLUE (-7845 407);
DISPLAY INVISIBLE (-7845 407);
FORCEPROP 1 LAST SIZE 1B
J 0
(-7725 400);
DISPLAY 1.170213 (-7725 400);
PAINT AQUA (-7725 400);
DISPLAY INVISIBLE (-7725 400);
FORCEPROP 2 LAST CDS_LIB mstr_symbols
J 0
(-7800 450);
PAINT ORANGE (-7800 450);
DISPLAY INVISIBLE (-7800 450);
FORCEPROP 1 LAST BODY_TYPE PLUMBING
J 0
(-7845 407);
DISPLAY 0.340426 (-7845 407);
PAINT GREEN (-7845 407);
DISPLAY INVISIBLE (-7845 407);
FORCEPROP 1 LAST PATH I3
J 0
(-7725 450);
DISPLAY 1.170213 (-7725 450);
PAINT AQUA (-7725 450);
DISPLAY INVISIBLE (-7725 450);
FORCEPROP 1 LAST HDL_POWER GND
J 0
(-7800 600);
DISPLAY 1.170213 (-7800 600);
PAINT GREEN (-7800 600);
DISPLAY INVISIBLE (-7800 600);
FORCEADD GND..1
(-5975 450);
FORCEPROP 3 LASTPIN (-5975 500) SIG_NAME GND\g
J 0
(-5965 510);
DISPLAY 0.659574 (-5965 510);
PAINT MONO (-5965 510);
DISPLAY INVISIBLE (-5965 510);
FORCEPROP 1 LAST VOLTAGE 0.0V
J 0
(-6020 407);
DISPLAY 0.340426 (-6020 407);
PAINT SKYBLUE (-6020 407);
DISPLAY INVISIBLE (-6020 407);
FORCEPROP 1 LAST SIZE 1B
J 0
(-5900 400);
DISPLAY 1.170213 (-5900 400);
PAINT AQUA (-5900 400);
DISPLAY INVISIBLE (-5900 400);
FORCEPROP 2 LAST CDS_LIB mstr_symbols
J 0
(-5975 450);
PAINT ORANGE (-5975 450);
DISPLAY INVISIBLE (-5975 450);
FORCEPROP 1 LAST BODY_TYPE PLUMBING
J 0
(-6020 407);
DISPLAY 0.340426 (-6020 407);
PAINT GREEN (-6020 407);
DISPLAY INVISIBLE (-6020 407);
FORCEPROP 1 LAST PATH I4
J 0
(-5900 450);
DISPLAY 1.170213 (-5900 450);
PAINT AQUA (-5900 450);
DISPLAY INVISIBLE (-5900 450);
FORCEPROP 1 LAST HDL_POWER GND
J 0
(-5975 600);
DISPLAY 1.170213 (-5975 600);
PAINT GREEN (-5975 600);
DISPLAY INVISIBLE (-5975 600);
FORCEADD GND..1
(-6275 450);
FORCEPROP 3 LASTPIN (-6275 500) SIG_NAME GND\g
J 0
(-6265 510);
DISPLAY 0.659574 (-6265 510);
PAINT MONO (-6265 510);
DISPLAY INVISIBLE (-6265 510);
FORCEPROP 1 LAST VOLTAGE 0.0V
J 0
(-6320 407);
DISPLAY 0.340426 (-6320 407);
PAINT SKYBLUE (-6320 407);
DISPLAY INVISIBLE (-6320 407);
FORCEPROP 1 LAST SIZE 1B
J 0
(-6200 400);
DISPLAY 1.170213 (-6200 400);
PAINT AQUA (-6200 400);
DISPLAY INVISIBLE (-6200 400);
FORCEPROP 2 LAST CDS_LIB mstr_symbols
J 0
(-6275 450);
PAINT ORANGE (-6275 450);
DISPLAY INVISIBLE (-6275 450);
FORCEPROP 1 LAST BODY_TYPE PLUMBING
J 0
(-6320 407);
DISPLAY 0.340426 (-6320 407);
PAINT GREEN (-6320 407);
DISPLAY INVISIBLE (-6320 407);
FORCEPROP 1 LAST PATH I5
J 0
(-6200 450);
DISPLAY 1.170213 (-6200 450);
PAINT AQUA (-6200 450);
DISPLAY INVISIBLE (-6200 450);
FORCEPROP 1 LAST HDL_POWER GND
J 0
(-6275 600);
DISPLAY 1.170213 (-6275 600);
PAINT GREEN (-6275 600);
DISPLAY INVISIBLE (-6275 600);
FORCEADD GND..1
(-4450 450);
FORCEPROP 3 LASTPIN (-4450 500) SIG_NAME GND\g
J 0
(-4440 510);
DISPLAY 0.659574 (-4440 510);
PAINT MONO (-4440 510);
DISPLAY INVISIBLE (-4440 510);
FORCEPROP 1 LAST VOLTAGE 0.0V
J 0
(-4495 407);
DISPLAY 0.340426 (-4495 407);
PAINT SKYBLUE (-4495 407);
DISPLAY INVISIBLE (-4495 407);
FORCEPROP 1 LAST SIZE 1B
J 0
(-4375 400);
DISPLAY 1.170213 (-4375 400);
PAINT AQUA (-4375 400);
DISPLAY INVISIBLE (-4375 400);
FORCEPROP 2 LAST CDS_LIB mstr_symbols
J 0
(-4450 450);
PAINT ORANGE (-4450 450);
DISPLAY INVISIBLE (-4450 450);
FORCEPROP 1 LAST BODY_TYPE PLUMBING
J 0
(-4495 407);
DISPLAY 0.340426 (-4495 407);
PAINT GREEN (-4495 407);
DISPLAY INVISIBLE (-4495 407);
FORCEPROP 1 LAST PATH I6
J 0
(-4375 450);
DISPLAY 1.170213 (-4375 450);
PAINT AQUA (-4375 450);
DISPLAY INVISIBLE (-4375 450);
FORCEPROP 1 LAST HDL_POWER GND
J 0
(-4450 600);
DISPLAY 1.170213 (-4450 600);
PAINT GREEN (-4450 600);
DISPLAY INVISIBLE (-4450 600);
FORCEADD GND..1
(-4150 450);
FORCEPROP 3 LASTPIN (-4150 500) SIG_NAME GND\g
J 0
(-4140 510);
DISPLAY 0.659574 (-4140 510);
PAINT MONO (-4140 510);
DISPLAY INVISIBLE (-4140 510);
FORCEPROP 1 LAST VOLTAGE 0.0V
J 0
(-4195 407);
DISPLAY 0.340426 (-4195 407);
PAINT SKYBLUE (-4195 407);
DISPLAY INVISIBLE (-4195 407);
FORCEPROP 2 LAST CDS_LIB mstr_symbols
J 0
(-4150 450);
PAINT ORANGE (-4150 450);
DISPLAY INVISIBLE (-4150 450);
FORCEPROP 1 LAST SIZE 1B
J 0
(-4075 400);
DISPLAY 1.170213 (-4075 400);
PAINT AQUA (-4075 400);
DISPLAY INVISIBLE (-4075 400);
FORCEPROP 1 LAST BODY_TYPE PLUMBING
J 0
(-4195 407);
DISPLAY 0.340426 (-4195 407);
PAINT GREEN (-4195 407);
DISPLAY INVISIBLE (-4195 407);
FORCEPROP 1 LAST PATH I9
J 0
(-4075 450);
DISPLAY 0.872340 (-4075 450);
PAINT AQUA (-4075 450);
DISPLAY INVISIBLE (-4075 450);
FORCEPROP 1 LAST HDL_POWER GND
J 0
(-4150 600);
DISPLAY 1.170213 (-4150 600);
PAINT GREEN (-4150 600);
DISPLAY INVISIBLE (-4150 600);
FORCEADD PRELIM..10
(-1440 2565);
PAINT GRAY (-1440 2565);
FORCEPROP 2 LAST CDS_LIB mstr_misc
J 0
(-1440 2565);
PAINT ORANGE (-1440 2565);
DISPLAY INVISIBLE (-1440 2565);
FORCEPROP 1 LAST COMMENT_BODY TRUE
J 0
(-1440 2565);
PAINT ORANGE (-1440 2565);
DISPLAY INVISIBLE (-1440 2565);
FORCEADD INTEL_CORP_BPAGE..1
(-300 25);
FORCEPROP 1 LAST CDS_CON_LAST_MODIFIED Fri Jun 16 17:48:15 2017
J 0
(-1725 350);
DISPLAY 1.340426 (-1725 350);
PAINT GREEN (-1725 350);
DISPLAY INVISIBLE (-1725 350);
FORCEPROP 1 LAST CUSTOM_TXT_CDS <CURRENT_DESIGN_SHEET> OF <TOTAL_DESIGN_SHEETS>
J 0
(-800 50);
PAINT ORANGE (-800 50);
FORCEPROP 1 LAST CUSTOM_TXT_CDS <CON_LAST_MODIFIED>
J 0
(-4300 125);
PAINT ORANGE (-4300 125);
FORCEPROP 2 LAST CUSTOM_TXT_CDS <XR_PAGE_TITLE>
J 0
(-8190 5275);
DISPLAY 0.638298 (-8190 5275);
PAINT PINK (-8190 5275);
DISPLAY INVISIBLE (-8190 5275);
FORCEPROP 1 LAST SCH_TITLE SKYLAKE - SKT0 - 20 OF 21
J 0
(-8250 75);
DISPLAY 1.212766 (-8250 75);
PAINT GREEN (-8250 75);
FORCEPROP 2 LAST CDS_LIB mstr_symbols
J 0
(-300 25);
PAINT ORANGE (-300 25);
DISPLAY INVISIBLE (-300 25);
FORCEPROP 2 LAST PAGE_BORDER TRUE
J 0
(-8190 5275);
DISPLAY 0.851064 (-8190 5275);
PAINT PINK (-8190 5275);
DISPLAY INVISIBLE (-8190 5275);
FORCEPROP 1 LAST COMMENT_BODY TRUE
J 0
(-288 37);
DISPLAY 0.638298 (-288 37);
PAINT GREEN (-288 37);
DISPLAY INVISIBLE (-288 37);
FORCEPROP 2 LAST CDS_XR_PAGE_TITLE CR-40 : @BASEBOARD_FAB2_LIB.BASEBOARD_FAB2(SCH_1):PAGE40
J 0
(-8190 5275);
DISPLAY 0.638298 (-8190 5275);
PAINT PINK (-8190 5275);
DISPLAY INVISIBLE (-8190 5275);
FORCEADD PRELIM..10
(-3390 2565);
PAINT GRAY (-3390 2565);
FORCEPROP 2 LAST CDS_LIB mstr_misc
J 0
(-3390 2565);
PAINT ORANGE (-3390 2565);
DISPLAY INVISIBLE (-3390 2565);
FORCEPROP 1 LAST COMMENT_BODY TRUE
J 0
(-3390 2565);
PAINT ORANGE (-3390 2565);
DISPLAY INVISIBLE (-3390 2565);
FORCEADD PRELIM..10
(-5190 2565);
PAINT GRAY (-5190 2565);
FORCEPROP 2 LAST CDS_LIB mstr_misc
J 0
(-5190 2565);
PAINT ORANGE (-5190 2565);
DISPLAY INVISIBLE (-5190 2565);
FORCEPROP 1 LAST COMMENT_BODY TRUE
J 0
(-5190 2565);
PAINT ORANGE (-5190 2565);
DISPLAY INVISIBLE (-5190 2565);
FORCEADD PRELIM..10
(-7040 2565);
PAINT GRAY (-7040 2565);
FORCEPROP 2 LAST CDS_LIB mstr_misc
J 0
(-7040 2565);
PAINT ORANGE (-7040 2565);
DISPLAY INVISIBLE (-7040 2565);
FORCEPROP 1 LAST COMMENT_BODY TRUE
J 0
(-7040 2565);
PAINT ORANGE (-7040 2565);
DISPLAY INVISIBLE (-7040 2565);
FORCEADD DESIGN_NOTE..1
(-6625 225);
FORCEPROP 0 LAST L1 CPU SYMBOLS 1-30 ARE PRELIMINARY AND SUBJECT TO CHANGE
J 0
(-6825 100);
DISPLAY 1.021277 (-6825 100);
PAINT ORANGE (-6825 100);
FORCEPROP 2 LAST CDS_LIB mstr_symbols
J 0
(-6625 225);
PAINT ORANGE (-6625 225);
DISPLAY INVISIBLE (-6625 225);
FORCEPROP 1 LAST COMMENT_BODY TRUE
J 0
(-6600 325);
DISPLAY 0.978723 (-6600 325);
PAINT ORANGE (-6600 325);
DISPLAY INVISIBLE (-6600 325);
WIRE 16 -1 (-2625 625)(-2625 500);
WIRE 16 -1 (-2625 675)(-2625 625);
WIRE 16 -1 (-2800 625)(-2625 625);
WIRE 16 -1 (-2625 725)(-2625 675);
WIRE 16 -1 (-2800 675)(-2625 675);
WIRE 16 -1 (-2625 775)(-2625 725);
WIRE 16 -1 (-2800 725)(-2625 725);
WIRE 16 -1 (-2625 825)(-2625 775);
WIRE 16 -1 (-2800 775)(-2625 775);
WIRE 16 -1 (-2625 875)(-2625 825);
WIRE 16 -1 (-2800 825)(-2625 825);
WIRE 16 -1 (-2625 925)(-2625 875);
WIRE 16 -1 (-2800 875)(-2625 875);
WIRE 16 -1 (-2625 975)(-2625 925);
WIRE 16 -1 (-2800 925)(-2625 925);
WIRE 16 -1 (-2625 1025)(-2625 975);
WIRE 16 -1 (-2800 975)(-2625 975);
WIRE 16 -1 (-2625 1075)(-2625 1025);
WIRE 16 -1 (-2800 1025)(-2625 1025);
WIRE 16 -1 (-2625 1125)(-2625 1075);
WIRE 16 -1 (-2800 1075)(-2625 1075);
WIRE 16 -1 (-2625 1175)(-2625 1125);
WIRE 16 -1 (-2800 1125)(-2625 1125);
WIRE 16 -1 (-2625 1225)(-2625 1175);
WIRE 16 -1 (-2800 1175)(-2625 1175);
WIRE 16 -1 (-2625 1275)(-2625 1225);
WIRE 16 -1 (-2800 1225)(-2625 1225);
WIRE 16 -1 (-2625 1325)(-2625 1275);
WIRE 16 -1 (-2800 1275)(-2625 1275);
WIRE 16 -1 (-2625 1375)(-2625 1325);
WIRE 16 -1 (-2800 1325)(-2625 1325);
WIRE 16 -1 (-2625 1425)(-2625 1375);
WIRE 16 -1 (-2800 1375)(-2625 1375);
WIRE 16 -1 (-2625 1475)(-2625 1425);
WIRE 16 -1 (-2800 1425)(-2625 1425);
WIRE 16 -1 (-2625 1525)(-2625 1475);
WIRE 16 -1 (-2800 1475)(-2625 1475);
WIRE 16 -1 (-2625 1575)(-2625 1525);
WIRE 16 -1 (-2800 1525)(-2625 1525);
WIRE 16 -1 (-2625 1625)(-2625 1575);
WIRE 16 -1 (-2800 1575)(-2625 1575);
WIRE 16 -1 (-2625 1675)(-2625 1625);
WIRE 16 -1 (-2800 1625)(-2625 1625);
WIRE 16 -1 (-2625 1725)(-2625 1675);
WIRE 16 -1 (-2800 1675)(-2625 1675);
WIRE 16 -1 (-2625 1775)(-2625 1725);
WIRE 16 -1 (-2800 1725)(-2625 1725);
WIRE 16 -1 (-2625 1825)(-2625 1775);
WIRE 16 -1 (-2800 1775)(-2625 1775);
WIRE 16 -1 (-2625 1875)(-2625 1825);
WIRE 16 -1 (-2800 1825)(-2625 1825);
WIRE 16 -1 (-2625 1925)(-2625 1875);
WIRE 16 -1 (-2800 1875)(-2625 1875);
WIRE 16 -1 (-2625 1975)(-2625 1925);
WIRE 16 -1 (-2800 1925)(-2625 1925);
WIRE 16 -1 (-2625 2025)(-2625 1975);
WIRE 16 -1 (-2800 1975)(-2625 1975);
WIRE 16 -1 (-2625 2075)(-2625 2025);
WIRE 16 -1 (-2800 2025)(-2625 2025);
WIRE 16 -1 (-2625 2125)(-2625 2075);
WIRE 16 -1 (-2800 2075)(-2625 2075);
WIRE 16 -1 (-2625 2175)(-2625 2125);
WIRE 16 -1 (-2800 2125)(-2625 2125);
WIRE 16 -1 (-2625 2225)(-2625 2175);
WIRE 16 -1 (-2800 2175)(-2625 2175);
WIRE 16 -1 (-2625 2275)(-2625 2225);
WIRE 16 -1 (-2800 2225)(-2625 2225);
WIRE 16 -1 (-2625 2325)(-2625 2275);
WIRE 16 -1 (-2800 2275)(-2625 2275);
WIRE 16 -1 (-2625 2375)(-2625 2325);
WIRE 16 -1 (-2800 2325)(-2625 2325);
WIRE 16 -1 (-2625 2425)(-2625 2375);
WIRE 16 -1 (-2800 2375)(-2625 2375);
WIRE 16 -1 (-2625 2475)(-2625 2425);
WIRE 16 -1 (-2800 2425)(-2625 2425);
WIRE 16 -1 (-2625 2525)(-2625 2475);
WIRE 16 -1 (-2800 2475)(-2625 2475);
WIRE 16 -1 (-2625 2575)(-2625 2525);
WIRE 16 -1 (-2800 2525)(-2625 2525);
WIRE 16 -1 (-2625 2625)(-2625 2575);
WIRE 16 -1 (-2800 2575)(-2625 2575);
WIRE 16 -1 (-2625 2675)(-2625 2625);
WIRE 16 -1 (-2800 2625)(-2625 2625);
WIRE 16 -1 (-2625 2725)(-2625 2675);
WIRE 16 -1 (-2800 2675)(-2625 2675);
WIRE 16 -1 (-2625 2775)(-2625 2725);
WIRE 16 -1 (-2800 2725)(-2625 2725);
WIRE 16 -1 (-2625 2825)(-2625 2775);
WIRE 16 -1 (-2800 2775)(-2625 2775);
WIRE 16 -1 (-2625 2875)(-2625 2825);
WIRE 16 -1 (-2800 2825)(-2625 2825);
WIRE 16 -1 (-2625 2925)(-2625 2875);
WIRE 16 -1 (-2800 2875)(-2625 2875);
WIRE 16 -1 (-2625 2975)(-2625 2925);
WIRE 16 -1 (-2800 2925)(-2625 2925);
WIRE 16 -1 (-2625 3025)(-2625 2975);
WIRE 16 -1 (-2800 2975)(-2625 2975);
WIRE 16 -1 (-2625 3075)(-2625 3025);
WIRE 16 -1 (-2800 3025)(-2625 3025);
WIRE 16 -1 (-2625 3125)(-2625 3075);
WIRE 16 -1 (-2800 3075)(-2625 3075);
WIRE 16 -1 (-2625 3175)(-2625 3125);
WIRE 16 -1 (-2800 3125)(-2625 3125);
WIRE 16 -1 (-2625 3225)(-2625 3175);
WIRE 16 -1 (-2800 3175)(-2625 3175);
WIRE 16 -1 (-2625 3275)(-2625 3225);
WIRE 16 -1 (-2800 3225)(-2625 3225);
WIRE 16 -1 (-2625 3325)(-2625 3275);
WIRE 16 -1 (-2800 3275)(-2625 3275);
WIRE 16 -1 (-2625 3375)(-2625 3325);
WIRE 16 -1 (-2800 3325)(-2625 3325);
WIRE 16 -1 (-2625 3425)(-2625 3375);
WIRE 16 -1 (-2800 3375)(-2625 3375);
WIRE 16 -1 (-2625 3475)(-2625 3425);
WIRE 16 -1 (-2800 3425)(-2625 3425);
WIRE 16 -1 (-2625 3525)(-2625 3475);
WIRE 16 -1 (-2800 3475)(-2625 3475);
WIRE 16 -1 (-2625 3575)(-2625 3525);
WIRE 16 -1 (-2800 3525)(-2625 3525);
WIRE 16 -1 (-2625 3625)(-2625 3575);
WIRE 16 -1 (-2800 3575)(-2625 3575);
WIRE 16 -1 (-2625 3675)(-2625 3625);
WIRE 16 -1 (-2800 3625)(-2625 3625);
WIRE 16 -1 (-2625 3725)(-2625 3675);
WIRE 16 -1 (-2800 3675)(-2625 3675);
WIRE 16 -1 (-2625 3775)(-2625 3725);
WIRE 16 -1 (-2800 3725)(-2625 3725);
WIRE 16 -1 (-2625 3825)(-2625 3775);
WIRE 16 -1 (-2800 3775)(-2625 3775);
WIRE 16 -1 (-2625 3875)(-2625 3825);
WIRE 16 -1 (-2800 3825)(-2625 3825);
WIRE 16 -1 (-2625 3925)(-2625 3875);
WIRE 16 -1 (-2800 3875)(-2625 3875);
WIRE 16 -1 (-2625 3975)(-2625 3925);
WIRE 16 -1 (-2800 3925)(-2625 3925);
WIRE 16 -1 (-2625 4025)(-2625 3975);
WIRE 16 -1 (-2800 3975)(-2625 3975);
WIRE 16 -1 (-2625 4075)(-2625 4025);
WIRE 16 -1 (-2800 4025)(-2625 4025);
WIRE 16 -1 (-2625 4125)(-2625 4075);
WIRE 16 -1 (-2800 4075)(-2625 4075);
WIRE 16 -1 (-2625 4175)(-2625 4125);
WIRE 16 -1 (-2800 4125)(-2625 4125);
WIRE 16 -1 (-2625 4225)(-2625 4175);
WIRE 16 -1 (-2800 4175)(-2625 4175);
WIRE 16 -1 (-2625 4275)(-2625 4225);
WIRE 16 -1 (-2800 4225)(-2625 4225);
WIRE 16 -1 (-2625 4325)(-2625 4275);
WIRE 16 -1 (-2800 4275)(-2625 4275);
WIRE 16 -1 (-2625 4375)(-2625 4325);
WIRE 16 -1 (-2800 4325)(-2625 4325);
WIRE 16 -1 (-2625 4425)(-2625 4375);
WIRE 16 -1 (-2800 4375)(-2625 4375);
WIRE 16 -1 (-2625 4475)(-2625 4425);
WIRE 16 -1 (-2800 4425)(-2625 4425);
WIRE 16 -1 (-2625 4525)(-2625 4475);
WIRE 16 -1 (-2800 4475)(-2625 4475);
WIRE 16 -1 (-2625 4575)(-2625 4525);
WIRE 16 -1 (-2800 4525)(-2625 4525);
WIRE 16 -1 (-2800 4575)(-2625 4575);
WIRE 16 -1 (-775 625)(-775 500);
WIRE 16 -1 (-775 675)(-775 625);
WIRE 16 -1 (-950 625)(-775 625);
WIRE 16 -1 (-775 725)(-775 675);
WIRE 16 -1 (-950 675)(-775 675);
WIRE 16 -1 (-775 775)(-775 725);
WIRE 16 -1 (-950 725)(-775 725);
WIRE 16 -1 (-775 825)(-775 775);
WIRE 16 -1 (-950 775)(-775 775);
WIRE 16 -1 (-775 875)(-775 825);
WIRE 16 -1 (-950 825)(-775 825);
WIRE 16 -1 (-775 925)(-775 875);
WIRE 16 -1 (-950 875)(-775 875);
WIRE 16 -1 (-775 975)(-775 925);
WIRE 16 -1 (-950 925)(-775 925);
WIRE 16 -1 (-775 1025)(-775 975);
WIRE 16 -1 (-950 975)(-775 975);
WIRE 16 -1 (-775 1075)(-775 1025);
WIRE 16 -1 (-950 1025)(-775 1025);
WIRE 16 -1 (-775 1125)(-775 1075);
WIRE 16 -1 (-950 1075)(-775 1075);
WIRE 16 -1 (-775 1175)(-775 1125);
WIRE 16 -1 (-950 1125)(-775 1125);
WIRE 16 -1 (-775 1225)(-775 1175);
WIRE 16 -1 (-950 1175)(-775 1175);
WIRE 16 -1 (-775 1275)(-775 1225);
WIRE 16 -1 (-950 1225)(-775 1225);
WIRE 16 -1 (-775 1325)(-775 1275);
WIRE 16 -1 (-950 1275)(-775 1275);
WIRE 16 -1 (-775 1375)(-775 1325);
WIRE 16 -1 (-950 1325)(-775 1325);
WIRE 16 -1 (-775 1425)(-775 1375);
WIRE 16 -1 (-950 1375)(-775 1375);
WIRE 16 -1 (-775 1475)(-775 1425);
WIRE 16 -1 (-950 1425)(-775 1425);
WIRE 16 -1 (-775 1525)(-775 1475);
WIRE 16 -1 (-950 1475)(-775 1475);
WIRE 16 -1 (-775 1575)(-775 1525);
WIRE 16 -1 (-950 1525)(-775 1525);
WIRE 16 -1 (-775 1625)(-775 1575);
WIRE 16 -1 (-950 1575)(-775 1575);
WIRE 16 -1 (-775 1675)(-775 1625);
WIRE 16 -1 (-950 1625)(-775 1625);
WIRE 16 -1 (-775 1725)(-775 1675);
WIRE 16 -1 (-950 1675)(-775 1675);
WIRE 16 -1 (-775 1775)(-775 1725);
WIRE 16 -1 (-950 1725)(-775 1725);
WIRE 16 -1 (-775 1825)(-775 1775);
WIRE 16 -1 (-950 1775)(-775 1775);
WIRE 16 -1 (-775 1875)(-775 1825);
WIRE 16 -1 (-950 1825)(-775 1825);
WIRE 16 -1 (-775 1925)(-775 1875);
WIRE 16 -1 (-950 1875)(-775 1875);
WIRE 16 -1 (-775 1975)(-775 1925);
WIRE 16 -1 (-950 1925)(-775 1925);
WIRE 16 -1 (-775 2025)(-775 1975);
WIRE 16 -1 (-950 1975)(-775 1975);
WIRE 16 -1 (-775 2075)(-775 2025);
WIRE 16 -1 (-950 2025)(-775 2025);
WIRE 16 -1 (-775 2125)(-775 2075);
WIRE 16 -1 (-950 2075)(-775 2075);
WIRE 16 -1 (-775 2175)(-775 2125);
WIRE 16 -1 (-950 2125)(-775 2125);
WIRE 16 -1 (-775 2225)(-775 2175);
WIRE 16 -1 (-950 2175)(-775 2175);
WIRE 16 -1 (-775 2275)(-775 2225);
WIRE 16 -1 (-950 2225)(-775 2225);
WIRE 16 -1 (-775 2325)(-775 2275);
WIRE 16 -1 (-950 2275)(-775 2275);
WIRE 16 -1 (-775 2375)(-775 2325);
WIRE 16 -1 (-950 2325)(-775 2325);
WIRE 16 -1 (-775 2425)(-775 2375);
WIRE 16 -1 (-950 2375)(-775 2375);
WIRE 16 -1 (-775 2475)(-775 2425);
WIRE 16 -1 (-950 2425)(-775 2425);
WIRE 16 -1 (-775 2525)(-775 2475);
WIRE 16 -1 (-950 2475)(-775 2475);
WIRE 16 -1 (-775 2575)(-775 2525);
WIRE 16 -1 (-950 2525)(-775 2525);
WIRE 16 -1 (-775 2625)(-775 2575);
WIRE 16 -1 (-950 2575)(-775 2575);
WIRE 16 -1 (-775 2675)(-775 2625);
WIRE 16 -1 (-950 2625)(-775 2625);
WIRE 16 -1 (-775 2725)(-775 2675);
WIRE 16 -1 (-950 2675)(-775 2675);
WIRE 16 -1 (-775 2775)(-775 2725);
WIRE 16 -1 (-950 2725)(-775 2725);
WIRE 16 -1 (-775 2825)(-775 2775);
WIRE 16 -1 (-950 2775)(-775 2775);
WIRE 16 -1 (-775 2875)(-775 2825);
WIRE 16 -1 (-950 2825)(-775 2825);
WIRE 16 -1 (-775 2925)(-775 2875);
WIRE 16 -1 (-950 2875)(-775 2875);
WIRE 16 -1 (-775 2975)(-775 2925);
WIRE 16 -1 (-950 2925)(-775 2925);
WIRE 16 -1 (-775 3025)(-775 2975);
WIRE 16 -1 (-950 2975)(-775 2975);
WIRE 16 -1 (-775 3075)(-775 3025);
WIRE 16 -1 (-950 3025)(-775 3025);
WIRE 16 -1 (-775 3125)(-775 3075);
WIRE 16 -1 (-950 3075)(-775 3075);
WIRE 16 -1 (-775 3175)(-775 3125);
WIRE 16 -1 (-950 3125)(-775 3125);
WIRE 16 -1 (-775 3225)(-775 3175);
WIRE 16 -1 (-950 3175)(-775 3175);
WIRE 16 -1 (-775 3275)(-775 3225);
WIRE 16 -1 (-950 3225)(-775 3225);
WIRE 16 -1 (-775 3325)(-775 3275);
WIRE 16 -1 (-950 3275)(-775 3275);
WIRE 16 -1 (-775 3375)(-775 3325);
WIRE 16 -1 (-950 3325)(-775 3325);
WIRE 16 -1 (-775 3425)(-775 3375);
WIRE 16 -1 (-950 3375)(-775 3375);
WIRE 16 -1 (-775 3475)(-775 3425);
WIRE 16 -1 (-950 3425)(-775 3425);
WIRE 16 -1 (-775 3525)(-775 3475);
WIRE 16 -1 (-950 3475)(-775 3475);
WIRE 16 -1 (-775 3575)(-775 3525);
WIRE 16 -1 (-950 3525)(-775 3525);
WIRE 16 -1 (-775 3625)(-775 3575);
WIRE 16 -1 (-950 3575)(-775 3575);
WIRE 16 -1 (-775 3675)(-775 3625);
WIRE 16 -1 (-950 3625)(-775 3625);
WIRE 16 -1 (-775 3725)(-775 3675);
WIRE 16 -1 (-950 3675)(-775 3675);
WIRE 16 -1 (-775 3775)(-775 3725);
WIRE 16 -1 (-950 3725)(-775 3725);
WIRE 16 -1 (-775 3825)(-775 3775);
WIRE 16 -1 (-950 3775)(-775 3775);
WIRE 16 -1 (-775 3875)(-775 3825);
WIRE 16 -1 (-950 3825)(-775 3825);
WIRE 16 -1 (-775 3925)(-775 3875);
WIRE 16 -1 (-950 3875)(-775 3875);
WIRE 16 -1 (-775 3975)(-775 3925);
WIRE 16 -1 (-950 3925)(-775 3925);
WIRE 16 -1 (-775 4025)(-775 3975);
WIRE 16 -1 (-950 3975)(-775 3975);
WIRE 16 -1 (-775 4075)(-775 4025);
WIRE 16 -1 (-950 4025)(-775 4025);
WIRE 16 -1 (-775 4125)(-775 4075);
WIRE 16 -1 (-950 4075)(-775 4075);
WIRE 16 -1 (-775 4175)(-775 4125);
WIRE 16 -1 (-950 4125)(-775 4125);
WIRE 16 -1 (-775 4225)(-775 4175);
WIRE 16 -1 (-950 4175)(-775 4175);
WIRE 16 -1 (-775 4275)(-775 4225);
WIRE 16 -1 (-950 4225)(-775 4225);
WIRE 16 -1 (-775 4325)(-775 4275);
WIRE 16 -1 (-950 4275)(-775 4275);
WIRE 16 -1 (-775 4375)(-775 4325);
WIRE 16 -1 (-950 4325)(-775 4325);
WIRE 16 -1 (-775 4425)(-775 4375);
WIRE 16 -1 (-950 4375)(-775 4375);
WIRE 16 -1 (-775 4475)(-775 4425);
WIRE 16 -1 (-950 4425)(-775 4425);
WIRE 16 -1 (-775 4525)(-775 4475);
WIRE 16 -1 (-950 4475)(-775 4475);
WIRE 16 -1 (-775 4575)(-775 4525);
WIRE 16 -1 (-950 4525)(-775 4525);
WIRE 16 -1 (-950 4575)(-775 4575);
WIRE 16 -1 (-2325 625)(-2325 525);
WIRE 16 -1 (-2325 675)(-2325 625);
WIRE 16 -1 (-2325 625)(-2150 625);
WIRE 16 -1 (-2325 725)(-2325 675);
WIRE 16 -1 (-2150 675)(-2325 675);
WIRE 16 -1 (-2325 775)(-2325 725);
WIRE 16 -1 (-2150 725)(-2325 725);
WIRE 16 -1 (-2325 825)(-2325 775);
WIRE 16 -1 (-2150 775)(-2325 775);
WIRE 16 -1 (-2325 875)(-2325 825);
WIRE 16 -1 (-2325 825)(-2150 825);
WIRE 16 -1 (-2325 925)(-2325 875);
WIRE 16 -1 (-2150 875)(-2325 875);
WIRE 16 -1 (-2325 975)(-2325 925);
WIRE 16 -1 (-2150 925)(-2325 925);
WIRE 16 -1 (-2325 1025)(-2325 975);
WIRE 16 -1 (-2150 975)(-2325 975);
WIRE 16 -1 (-2325 1075)(-2325 1025);
WIRE 16 -1 (-2150 1025)(-2325 1025);
WIRE 16 -1 (-2325 1125)(-2325 1075);
WIRE 16 -1 (-2150 1075)(-2325 1075);
WIRE 16 -1 (-2325 1175)(-2325 1125);
WIRE 16 -1 (-2150 1125)(-2325 1125);
WIRE 16 -1 (-2325 1225)(-2325 1175);
WIRE 16 -1 (-2150 1175)(-2325 1175);
WIRE 16 -1 (-2325 1275)(-2325 1225);
WIRE 16 -1 (-2150 1225)(-2325 1225);
WIRE 16 -1 (-2325 1325)(-2325 1275);
WIRE 16 -1 (-2150 1275)(-2325 1275);
WIRE 16 -1 (-2325 1375)(-2325 1325);
WIRE 16 -1 (-2150 1325)(-2325 1325);
WIRE 16 -1 (-2325 1425)(-2325 1375);
WIRE 16 -1 (-2150 1375)(-2325 1375);
WIRE 16 -1 (-2325 1475)(-2325 1425);
WIRE 16 -1 (-2150 1425)(-2325 1425);
WIRE 16 -1 (-2325 1525)(-2325 1475);
WIRE 16 -1 (-2150 1475)(-2325 1475);
WIRE 16 -1 (-2325 1575)(-2325 1525);
WIRE 16 -1 (-2150 1525)(-2325 1525);
WIRE 16 -1 (-2325 1625)(-2325 1575);
WIRE 16 -1 (-2150 1575)(-2325 1575);
WIRE 16 -1 (-2325 1675)(-2325 1625);
WIRE 16 -1 (-2150 1625)(-2325 1625);
WIRE 16 -1 (-2325 1725)(-2325 1675);
WIRE 16 -1 (-2150 1675)(-2325 1675);
WIRE 16 -1 (-2325 1775)(-2325 1725);
WIRE 16 -1 (-2150 1725)(-2325 1725);
WIRE 16 -1 (-2325 1825)(-2325 1775);
WIRE 16 -1 (-2150 1775)(-2325 1775);
WIRE 16 -1 (-2325 1875)(-2325 1825);
WIRE 16 -1 (-2150 1825)(-2325 1825);
WIRE 16 -1 (-2325 1925)(-2325 1875);
WIRE 16 -1 (-2150 1875)(-2325 1875);
WIRE 16 -1 (-2325 1975)(-2325 1925);
WIRE 16 -1 (-2150 1925)(-2325 1925);
WIRE 16 -1 (-2325 2025)(-2325 1975);
WIRE 16 -1 (-2150 1975)(-2325 1975);
WIRE 16 -1 (-2325 2075)(-2325 2025);
WIRE 16 -1 (-2150 2025)(-2325 2025);
WIRE 16 -1 (-2325 2125)(-2325 2075);
WIRE 16 -1 (-2150 2075)(-2325 2075);
WIRE 16 -1 (-2325 2175)(-2325 2125);
WIRE 16 -1 (-2150 2125)(-2325 2125);
WIRE 16 -1 (-2325 2225)(-2325 2175);
WIRE 16 -1 (-2150 2175)(-2325 2175);
WIRE 16 -1 (-2325 2275)(-2325 2225);
WIRE 16 -1 (-2150 2225)(-2325 2225);
WIRE 16 -1 (-2325 2325)(-2325 2275);
WIRE 16 -1 (-2150 2275)(-2325 2275);
WIRE 16 -1 (-2325 2375)(-2325 2325);
WIRE 16 -1 (-2150 2325)(-2325 2325);
WIRE 16 -1 (-2325 2425)(-2325 2375);
WIRE 16 -1 (-2150 2375)(-2325 2375);
WIRE 16 -1 (-2325 2475)(-2325 2425);
WIRE 16 -1 (-2150 2425)(-2325 2425);
WIRE 16 -1 (-2325 2525)(-2325 2475);
WIRE 16 -1 (-2150 2475)(-2325 2475);
WIRE 16 -1 (-2325 2575)(-2325 2525);
WIRE 16 -1 (-2150 2525)(-2325 2525);
WIRE 16 -1 (-2325 2625)(-2325 2575);
WIRE 16 -1 (-2150 2575)(-2325 2575);
WIRE 16 -1 (-2325 2675)(-2325 2625);
WIRE 16 -1 (-2150 2625)(-2325 2625);
WIRE 16 -1 (-2325 2725)(-2325 2675);
WIRE 16 -1 (-2150 2675)(-2325 2675);
WIRE 16 -1 (-2325 2775)(-2325 2725);
WIRE 16 -1 (-2150 2725)(-2325 2725);
WIRE 16 -1 (-2325 2825)(-2325 2775);
WIRE 16 -1 (-2150 2775)(-2325 2775);
WIRE 16 -1 (-2325 2875)(-2325 2825);
WIRE 16 -1 (-2150 2825)(-2325 2825);
WIRE 16 -1 (-2325 2925)(-2325 2875);
WIRE 16 -1 (-2150 2875)(-2325 2875);
WIRE 16 -1 (-2325 2975)(-2325 2925);
WIRE 16 -1 (-2150 2925)(-2325 2925);
WIRE 16 -1 (-2325 3025)(-2325 2975);
WIRE 16 -1 (-2150 2975)(-2325 2975);
WIRE 16 -1 (-2325 3075)(-2325 3025);
WIRE 16 -1 (-2150 3025)(-2325 3025);
WIRE 16 -1 (-2325 3125)(-2325 3075);
WIRE 16 -1 (-2150 3075)(-2325 3075);
WIRE 16 -1 (-2325 3175)(-2325 3125);
WIRE 16 -1 (-2150 3125)(-2325 3125);
WIRE 16 -1 (-2325 3225)(-2325 3175);
WIRE 16 -1 (-2150 3175)(-2325 3175);
WIRE 16 -1 (-2325 3275)(-2325 3225);
WIRE 16 -1 (-2150 3225)(-2325 3225);
WIRE 16 -1 (-2325 3325)(-2325 3275);
WIRE 16 -1 (-2150 3275)(-2325 3275);
WIRE 16 -1 (-2325 3375)(-2325 3325);
WIRE 16 -1 (-2150 3325)(-2325 3325);
WIRE 16 -1 (-2325 3425)(-2325 3375);
WIRE 16 -1 (-2150 3375)(-2325 3375);
WIRE 16 -1 (-2325 3475)(-2325 3425);
WIRE 16 -1 (-2150 3425)(-2325 3425);
WIRE 16 -1 (-2325 3525)(-2325 3475);
WIRE 16 -1 (-2150 3475)(-2325 3475);
WIRE 16 -1 (-2325 3575)(-2325 3525);
WIRE 16 -1 (-2150 3525)(-2325 3525);
WIRE 16 -1 (-2325 3625)(-2325 3575);
WIRE 16 -1 (-2150 3575)(-2325 3575);
WIRE 16 -1 (-2325 3675)(-2325 3625);
WIRE 16 -1 (-2150 3625)(-2325 3625);
WIRE 16 -1 (-2325 3725)(-2325 3675);
WIRE 16 -1 (-2150 3675)(-2325 3675);
WIRE 16 -1 (-2325 3775)(-2325 3725);
WIRE 16 -1 (-2150 3725)(-2325 3725);
WIRE 16 -1 (-2325 3825)(-2325 3775);
WIRE 16 -1 (-2150 3775)(-2325 3775);
WIRE 16 -1 (-2325 3875)(-2325 3825);
WIRE 16 -1 (-2150 3825)(-2325 3825);
WIRE 16 -1 (-2325 3925)(-2325 3875);
WIRE 16 -1 (-2150 3875)(-2325 3875);
WIRE 16 -1 (-2325 3975)(-2325 3925);
WIRE 16 -1 (-2150 3925)(-2325 3925);
WIRE 16 -1 (-2325 4025)(-2325 3975);
WIRE 16 -1 (-2150 3975)(-2325 3975);
WIRE 16 -1 (-2325 4075)(-2325 4025);
WIRE 16 -1 (-2150 4025)(-2325 4025);
WIRE 16 -1 (-2325 4125)(-2325 4075);
WIRE 16 -1 (-2150 4075)(-2325 4075);
WIRE 16 -1 (-2325 4175)(-2325 4125);
WIRE 16 -1 (-2150 4125)(-2325 4125);
WIRE 16 -1 (-2325 4225)(-2325 4175);
WIRE 16 -1 (-2150 4175)(-2325 4175);
WIRE 16 -1 (-2325 4275)(-2325 4225);
WIRE 16 -1 (-2150 4225)(-2325 4225);
WIRE 16 -1 (-2325 4325)(-2325 4275);
WIRE 16 -1 (-2150 4275)(-2325 4275);
WIRE 16 -1 (-2325 4375)(-2325 4325);
WIRE 16 -1 (-2150 4325)(-2325 4325);
WIRE 16 -1 (-2325 4425)(-2325 4375);
WIRE 16 -1 (-2150 4375)(-2325 4375);
WIRE 16 -1 (-2325 4475)(-2325 4425);
WIRE 16 -1 (-2150 4425)(-2325 4425);
WIRE 16 -1 (-2325 4525)(-2325 4475);
WIRE 16 -1 (-2150 4475)(-2325 4475);
WIRE 16 -1 (-2325 4575)(-2325 4525);
WIRE 16 -1 (-2150 4525)(-2325 4525);
WIRE 16 -1 (-2150 4575)(-2325 4575);
WIRE 16 -1 (-7800 625)(-7800 500);
WIRE 16 -1 (-7800 675)(-7800 625);
WIRE 16 -1 (-7650 625)(-7800 625);
WIRE 16 -1 (-7800 725)(-7800 675);
WIRE 16 -1 (-7650 675)(-7800 675);
WIRE 16 -1 (-7800 775)(-7800 725);
WIRE 16 -1 (-7650 725)(-7800 725);
WIRE 16 -1 (-7800 825)(-7800 775);
WIRE 16 -1 (-7650 775)(-7800 775);
WIRE 16 -1 (-7800 875)(-7800 825);
WIRE 16 -1 (-7650 825)(-7800 825);
WIRE 16 -1 (-7800 925)(-7800 875);
WIRE 16 -1 (-7650 875)(-7800 875);
WIRE 16 -1 (-7800 975)(-7800 925);
WIRE 16 -1 (-7650 925)(-7800 925);
WIRE 16 -1 (-7800 1025)(-7800 975);
WIRE 16 -1 (-7650 975)(-7800 975);
WIRE 16 -1 (-7800 1075)(-7800 1025);
WIRE 16 -1 (-7650 1025)(-7800 1025);
WIRE 16 -1 (-7800 1125)(-7800 1075);
WIRE 16 -1 (-7650 1075)(-7800 1075);
WIRE 16 -1 (-7800 1175)(-7800 1125);
WIRE 16 -1 (-7650 1125)(-7800 1125);
WIRE 16 -1 (-7800 1225)(-7800 1175);
WIRE 16 -1 (-7650 1175)(-7800 1175);
WIRE 16 -1 (-7800 1275)(-7800 1225);
WIRE 16 -1 (-7650 1225)(-7800 1225);
WIRE 16 -1 (-7800 1325)(-7800 1275);
WIRE 16 -1 (-7650 1275)(-7800 1275);
WIRE 16 -1 (-7800 1375)(-7800 1325);
WIRE 16 -1 (-7650 1325)(-7800 1325);
WIRE 16 -1 (-7800 1425)(-7800 1375);
WIRE 16 -1 (-7650 1375)(-7800 1375);
WIRE 16 -1 (-7800 1475)(-7800 1425);
WIRE 16 -1 (-7650 1425)(-7800 1425);
WIRE 16 -1 (-7800 1525)(-7800 1475);
WIRE 16 -1 (-7650 1475)(-7800 1475);
WIRE 16 -1 (-7800 1575)(-7800 1525);
WIRE 16 -1 (-7650 1525)(-7800 1525);
WIRE 16 -1 (-7800 1625)(-7800 1575);
WIRE 16 -1 (-7650 1575)(-7800 1575);
WIRE 16 -1 (-7800 1675)(-7800 1625);
WIRE 16 -1 (-7650 1625)(-7800 1625);
WIRE 16 -1 (-7800 1725)(-7800 1675);
WIRE 16 -1 (-7650 1675)(-7800 1675);
WIRE 16 -1 (-7800 1775)(-7800 1725);
WIRE 16 -1 (-7650 1725)(-7800 1725);
WIRE 16 -1 (-7800 1825)(-7800 1775);
WIRE 16 -1 (-7650 1775)(-7800 1775);
WIRE 16 -1 (-7800 1875)(-7800 1825);
WIRE 16 -1 (-7650 1825)(-7800 1825);
WIRE 16 -1 (-7800 1925)(-7800 1875);
WIRE 16 -1 (-7650 1875)(-7800 1875);
WIRE 16 -1 (-7800 1975)(-7800 1925);
WIRE 16 -1 (-7650 1925)(-7800 1925);
WIRE 16 -1 (-7800 2025)(-7800 1975);
WIRE 16 -1 (-7650 1975)(-7800 1975);
WIRE 16 -1 (-7800 2075)(-7800 2025);
WIRE 16 -1 (-7650 2025)(-7800 2025);
WIRE 16 -1 (-7800 2125)(-7800 2075);
WIRE 16 -1 (-7650 2075)(-7800 2075);
WIRE 16 -1 (-7800 2175)(-7800 2125);
WIRE 16 -1 (-7650 2125)(-7800 2125);
WIRE 16 -1 (-7800 2225)(-7800 2175);
WIRE 16 -1 (-7650 2175)(-7800 2175);
WIRE 16 -1 (-7800 2275)(-7800 2225);
WIRE 16 -1 (-7650 2225)(-7800 2225);
WIRE 16 -1 (-7800 2325)(-7800 2275);
WIRE 16 -1 (-7650 2275)(-7800 2275);
WIRE 16 -1 (-7800 2375)(-7800 2325);
WIRE 16 -1 (-7650 2325)(-7800 2325);
WIRE 16 -1 (-7800 2425)(-7800 2375);
WIRE 16 -1 (-7650 2375)(-7800 2375);
WIRE 16 -1 (-7800 2475)(-7800 2425);
WIRE 16 -1 (-7650 2425)(-7800 2425);
WIRE 16 -1 (-7800 2525)(-7800 2475);
WIRE 16 -1 (-7650 2475)(-7800 2475);
WIRE 16 -1 (-7800 2575)(-7800 2525);
WIRE 16 -1 (-7650 2525)(-7800 2525);
WIRE 16 -1 (-7800 2625)(-7800 2575);
WIRE 16 -1 (-7650 2575)(-7800 2575);
WIRE 16 -1 (-7800 2675)(-7800 2625);
WIRE 16 -1 (-7650 2625)(-7800 2625);
WIRE 16 -1 (-7800 2725)(-7800 2675);
WIRE 16 -1 (-7650 2675)(-7800 2675);
WIRE 16 -1 (-7800 2775)(-7800 2725);
WIRE 16 -1 (-7650 2725)(-7800 2725);
WIRE 16 -1 (-7800 2825)(-7800 2775);
WIRE 16 -1 (-7650 2775)(-7800 2775);
WIRE 16 -1 (-7800 2875)(-7800 2825);
WIRE 16 -1 (-7650 2825)(-7800 2825);
WIRE 16 -1 (-7800 2925)(-7800 2875);
WIRE 16 -1 (-7650 2875)(-7800 2875);
WIRE 16 -1 (-7800 2975)(-7800 2925);
WIRE 16 -1 (-7650 2925)(-7800 2925);
WIRE 16 -1 (-7800 3025)(-7800 2975);
WIRE 16 -1 (-7650 2975)(-7800 2975);
WIRE 16 -1 (-7800 3075)(-7800 3025);
WIRE 16 -1 (-7650 3025)(-7800 3025);
WIRE 16 -1 (-7800 3125)(-7800 3075);
WIRE 16 -1 (-7650 3075)(-7800 3075);
WIRE 16 -1 (-7800 3175)(-7800 3125);
WIRE 16 -1 (-7650 3125)(-7800 3125);
WIRE 16 -1 (-7800 3225)(-7800 3175);
WIRE 16 -1 (-7650 3175)(-7800 3175);
WIRE 16 -1 (-7800 3275)(-7800 3225);
WIRE 16 -1 (-7650 3225)(-7800 3225);
WIRE 16 -1 (-7800 3325)(-7800 3275);
WIRE 16 -1 (-7650 3275)(-7800 3275);
WIRE 16 -1 (-7800 3375)(-7800 3325);
WIRE 16 -1 (-7650 3325)(-7800 3325);
WIRE 16 -1 (-7800 3425)(-7800 3375);
WIRE 16 -1 (-7650 3375)(-7800 3375);
WIRE 16 -1 (-7800 3475)(-7800 3425);
WIRE 16 -1 (-7650 3425)(-7800 3425);
WIRE 16 -1 (-7800 3525)(-7800 3475);
WIRE 16 -1 (-7650 3475)(-7800 3475);
WIRE 16 -1 (-7800 3575)(-7800 3525);
WIRE 16 -1 (-7650 3525)(-7800 3525);
WIRE 16 -1 (-7800 3625)(-7800 3575);
WIRE 16 -1 (-7650 3575)(-7800 3575);
WIRE 16 -1 (-7800 3675)(-7800 3625);
WIRE 16 -1 (-7650 3625)(-7800 3625);
WIRE 16 -1 (-7800 3725)(-7800 3675);
WIRE 16 -1 (-7650 3675)(-7800 3675);
WIRE 16 -1 (-7800 3775)(-7800 3725);
WIRE 16 -1 (-7650 3725)(-7800 3725);
WIRE 16 -1 (-7800 3825)(-7800 3775);
WIRE 16 -1 (-7650 3775)(-7800 3775);
WIRE 16 -1 (-7800 3875)(-7800 3825);
WIRE 16 -1 (-7650 3825)(-7800 3825);
WIRE 16 -1 (-7800 3925)(-7800 3875);
WIRE 16 -1 (-7650 3875)(-7800 3875);
WIRE 16 -1 (-7800 3975)(-7800 3925);
WIRE 16 -1 (-7650 3925)(-7800 3925);
WIRE 16 -1 (-7800 4025)(-7800 3975);
WIRE 16 -1 (-7650 3975)(-7800 3975);
WIRE 16 -1 (-7800 4075)(-7800 4025);
WIRE 16 -1 (-7650 4025)(-7800 4025);
WIRE 16 -1 (-7800 4125)(-7800 4075);
WIRE 16 -1 (-7650 4075)(-7800 4075);
WIRE 16 -1 (-7800 4175)(-7800 4125);
WIRE 16 -1 (-7650 4125)(-7800 4125);
WIRE 16 -1 (-7800 4225)(-7800 4175);
WIRE 16 -1 (-7650 4175)(-7800 4175);
WIRE 16 -1 (-7800 4275)(-7800 4225);
WIRE 16 -1 (-7650 4225)(-7800 4225);
WIRE 16 -1 (-7800 4325)(-7800 4275);
WIRE 16 -1 (-7650 4275)(-7800 4275);
WIRE 16 -1 (-7800 4375)(-7800 4325);
WIRE 16 -1 (-7650 4325)(-7800 4325);
WIRE 16 -1 (-7800 4425)(-7800 4375);
WIRE 16 -1 (-7650 4375)(-7800 4375);
WIRE 16 -1 (-7800 4475)(-7800 4425);
WIRE 16 -1 (-7650 4425)(-7800 4425);
WIRE 16 -1 (-7800 4525)(-7800 4475);
WIRE 16 -1 (-7650 4475)(-7800 4475);
WIRE 16 -1 (-7800 4575)(-7800 4525);
WIRE 16 -1 (-7650 4525)(-7800 4525);
WIRE 16 -1 (-7650 4575)(-7800 4575);
WIRE 16 -1 (-5975 625)(-5975 500);
WIRE 16 -1 (-5975 675)(-5975 625);
WIRE 16 -1 (-5975 625)(-5825 625);
WIRE 16 -1 (-5975 725)(-5975 675);
WIRE 16 -1 (-5825 675)(-5975 675);
WIRE 16 -1 (-5975 775)(-5975 725);
WIRE 16 -1 (-5825 725)(-5975 725);
WIRE 16 -1 (-5975 825)(-5975 775);
WIRE 16 -1 (-5825 775)(-5975 775);
WIRE 16 -1 (-5975 875)(-5975 825);
WIRE 16 -1 (-5825 825)(-5975 825);
WIRE 16 -1 (-5975 925)(-5975 875);
WIRE 16 -1 (-5825 875)(-5975 875);
WIRE 16 -1 (-5975 975)(-5975 925);
WIRE 16 -1 (-5825 925)(-5975 925);
WIRE 16 -1 (-5975 1025)(-5975 975);
WIRE 16 -1 (-5825 975)(-5975 975);
WIRE 16 -1 (-5975 1075)(-5975 1025);
WIRE 16 -1 (-5825 1025)(-5975 1025);
WIRE 16 -1 (-5975 1125)(-5975 1075);
WIRE 16 -1 (-5825 1075)(-5975 1075);
WIRE 16 -1 (-5975 1175)(-5975 1125);
WIRE 16 -1 (-5825 1125)(-5975 1125);
WIRE 16 -1 (-5975 1225)(-5975 1175);
WIRE 16 -1 (-5825 1175)(-5975 1175);
WIRE 16 -1 (-5975 1275)(-5975 1225);
WIRE 16 -1 (-5825 1225)(-5975 1225);
WIRE 16 -1 (-5975 1325)(-5975 1275);
WIRE 16 -1 (-5825 1275)(-5975 1275);
WIRE 16 -1 (-5975 1375)(-5975 1325);
WIRE 16 -1 (-5825 1325)(-5975 1325);
WIRE 16 -1 (-5975 1425)(-5975 1375);
WIRE 16 -1 (-5825 1375)(-5975 1375);
WIRE 16 -1 (-5975 1475)(-5975 1425);
WIRE 16 -1 (-5825 1425)(-5975 1425);
WIRE 16 -1 (-5975 1525)(-5975 1475);
WIRE 16 -1 (-5825 1475)(-5975 1475);
WIRE 16 -1 (-5975 1575)(-5975 1525);
WIRE 16 -1 (-5825 1525)(-5975 1525);
WIRE 16 -1 (-5975 1625)(-5975 1575);
WIRE 16 -1 (-5825 1575)(-5975 1575);
WIRE 16 -1 (-5975 1675)(-5975 1625);
WIRE 16 -1 (-5825 1625)(-5975 1625);
WIRE 16 -1 (-5975 1725)(-5975 1675);
WIRE 16 -1 (-5825 1675)(-5975 1675);
WIRE 16 -1 (-5975 1775)(-5975 1725);
WIRE 16 -1 (-5825 1725)(-5975 1725);
WIRE 16 -1 (-5975 1825)(-5975 1775);
WIRE 16 -1 (-5825 1775)(-5975 1775);
WIRE 16 -1 (-5975 1875)(-5975 1825);
WIRE 16 -1 (-5825 1825)(-5975 1825);
WIRE 16 -1 (-5975 1925)(-5975 1875);
WIRE 16 -1 (-5825 1875)(-5975 1875);
WIRE 16 -1 (-5975 1975)(-5975 1925);
WIRE 16 -1 (-5825 1925)(-5975 1925);
WIRE 16 -1 (-5975 2025)(-5975 1975);
WIRE 16 -1 (-5825 1975)(-5975 1975);
WIRE 16 -1 (-5975 2075)(-5975 2025);
WIRE 16 -1 (-5825 2025)(-5975 2025);
WIRE 16 -1 (-5975 2125)(-5975 2075);
WIRE 16 -1 (-5825 2075)(-5975 2075);
WIRE 16 -1 (-5975 2175)(-5975 2125);
WIRE 16 -1 (-5825 2125)(-5975 2125);
WIRE 16 -1 (-5975 2225)(-5975 2175);
WIRE 16 -1 (-5825 2175)(-5975 2175);
WIRE 16 -1 (-5975 2275)(-5975 2225);
WIRE 16 -1 (-5825 2225)(-5975 2225);
WIRE 16 -1 (-5975 2325)(-5975 2275);
WIRE 16 -1 (-5825 2275)(-5975 2275);
WIRE 16 -1 (-5975 2375)(-5975 2325);
WIRE 16 -1 (-5825 2325)(-5975 2325);
WIRE 16 -1 (-5975 2425)(-5975 2375);
WIRE 16 -1 (-5825 2375)(-5975 2375);
WIRE 16 -1 (-5975 2475)(-5975 2425);
WIRE 16 -1 (-5825 2425)(-5975 2425);
WIRE 16 -1 (-5975 2525)(-5975 2475);
WIRE 16 -1 (-5825 2475)(-5975 2475);
WIRE 16 -1 (-5975 2575)(-5975 2525);
WIRE 16 -1 (-5825 2525)(-5975 2525);
WIRE 16 -1 (-5975 2625)(-5975 2575);
WIRE 16 -1 (-5825 2575)(-5975 2575);
WIRE 16 -1 (-5975 2675)(-5975 2625);
WIRE 16 -1 (-5825 2625)(-5975 2625);
WIRE 16 -1 (-5975 2725)(-5975 2675);
WIRE 16 -1 (-5825 2675)(-5975 2675);
WIRE 16 -1 (-5975 2775)(-5975 2725);
WIRE 16 -1 (-5825 2725)(-5975 2725);
WIRE 16 -1 (-5975 2825)(-5975 2775);
WIRE 16 -1 (-5825 2775)(-5975 2775);
WIRE 16 -1 (-5975 2875)(-5975 2825);
WIRE 16 -1 (-5825 2825)(-5975 2825);
WIRE 16 -1 (-5975 2925)(-5975 2875);
WIRE 16 -1 (-5825 2875)(-5975 2875);
WIRE 16 -1 (-5975 2975)(-5975 2925);
WIRE 16 -1 (-5825 2925)(-5975 2925);
WIRE 16 -1 (-5975 3025)(-5975 2975);
WIRE 16 -1 (-5825 2975)(-5975 2975);
WIRE 16 -1 (-5975 3075)(-5975 3025);
WIRE 16 -1 (-5825 3025)(-5975 3025);
WIRE 16 -1 (-5975 3125)(-5975 3075);
WIRE 16 -1 (-5825 3075)(-5975 3075);
WIRE 16 -1 (-5975 3175)(-5975 3125);
WIRE 16 -1 (-5825 3125)(-5975 3125);
WIRE 16 -1 (-5975 3225)(-5975 3175);
WIRE 16 -1 (-5825 3175)(-5975 3175);
WIRE 16 -1 (-5975 3275)(-5975 3225);
WIRE 16 -1 (-5825 3225)(-5975 3225);
WIRE 16 -1 (-5975 3325)(-5975 3275);
WIRE 16 -1 (-5825 3275)(-5975 3275);
WIRE 16 -1 (-5975 3375)(-5975 3325);
WIRE 16 -1 (-5825 3325)(-5975 3325);
WIRE 16 -1 (-5975 3425)(-5975 3375);
WIRE 16 -1 (-5825 3375)(-5975 3375);
WIRE 16 -1 (-5975 3475)(-5975 3425);
WIRE 16 -1 (-5825 3425)(-5975 3425);
WIRE 16 -1 (-5975 3525)(-5975 3475);
WIRE 16 -1 (-5825 3475)(-5975 3475);
WIRE 16 -1 (-5975 3575)(-5975 3525);
WIRE 16 -1 (-5825 3525)(-5975 3525);
WIRE 16 -1 (-5975 3625)(-5975 3575);
WIRE 16 -1 (-5825 3575)(-5975 3575);
WIRE 16 -1 (-5975 3675)(-5975 3625);
WIRE 16 -1 (-5825 3625)(-5975 3625);
WIRE 16 -1 (-5975 3725)(-5975 3675);
WIRE 16 -1 (-5825 3675)(-5975 3675);
WIRE 16 -1 (-5975 3775)(-5975 3725);
WIRE 16 -1 (-5825 3725)(-5975 3725);
WIRE 16 -1 (-5975 3825)(-5975 3775);
WIRE 16 -1 (-5825 3775)(-5975 3775);
WIRE 16 -1 (-5975 3875)(-5975 3825);
WIRE 16 -1 (-5825 3825)(-5975 3825);
WIRE 16 -1 (-5975 3925)(-5975 3875);
WIRE 16 -1 (-5825 3875)(-5975 3875);
WIRE 16 -1 (-5975 3975)(-5975 3925);
WIRE 16 -1 (-5825 3925)(-5975 3925);
WIRE 16 -1 (-5975 4025)(-5975 3975);
WIRE 16 -1 (-5825 3975)(-5975 3975);
WIRE 16 -1 (-5975 4075)(-5975 4025);
WIRE 16 -1 (-5825 4025)(-5975 4025);
WIRE 16 -1 (-5975 4125)(-5975 4075);
WIRE 16 -1 (-5825 4075)(-5975 4075);
WIRE 16 -1 (-5975 4175)(-5975 4125);
WIRE 16 -1 (-5825 4125)(-5975 4125);
WIRE 16 -1 (-5975 4225)(-5975 4175);
WIRE 16 -1 (-5825 4175)(-5975 4175);
WIRE 16 -1 (-5975 4275)(-5975 4225);
WIRE 16 -1 (-5825 4225)(-5975 4225);
WIRE 16 -1 (-5975 4325)(-5975 4275);
WIRE 16 -1 (-5825 4275)(-5975 4275);
WIRE 16 -1 (-5975 4375)(-5975 4325);
WIRE 16 -1 (-5825 4325)(-5975 4325);
WIRE 16 -1 (-5975 4375)(-5975 4425);
WIRE 16 -1 (-5825 4375)(-5975 4375);
WIRE 16 -1 (-5975 4425)(-5975 4475);
WIRE 16 -1 (-5825 4425)(-5975 4425);
WIRE 16 -1 (-5975 4525)(-5975 4475);
WIRE 16 -1 (-5825 4475)(-5975 4475);
WIRE 16 -1 (-5975 4575)(-5975 4525);
WIRE 16 -1 (-5825 4525)(-5975 4525);
WIRE 16 -1 (-5975 4575)(-5825 4575);
WIRE 16 -1 (-6275 625)(-6275 500);
WIRE 16 -1 (-6275 675)(-6275 625);
WIRE 16 -1 (-6450 625)(-6275 625);
WIRE 16 -1 (-6275 725)(-6275 675);
WIRE 16 -1 (-6450 675)(-6275 675);
WIRE 16 -1 (-6275 775)(-6275 725);
WIRE 16 -1 (-6450 725)(-6275 725);
WIRE 16 -1 (-6275 825)(-6275 775);
WIRE 16 -1 (-6450 775)(-6275 775);
WIRE 16 -1 (-6275 875)(-6275 825);
WIRE 16 -1 (-6450 825)(-6275 825);
WIRE 16 -1 (-6275 925)(-6275 875);
WIRE 16 -1 (-6450 875)(-6275 875);
WIRE 16 -1 (-6275 975)(-6275 925);
WIRE 16 -1 (-6450 925)(-6275 925);
WIRE 16 -1 (-6275 1025)(-6275 975);
WIRE 16 -1 (-6450 975)(-6275 975);
WIRE 16 -1 (-6275 1075)(-6275 1025);
WIRE 16 -1 (-6450 1025)(-6275 1025);
WIRE 16 -1 (-6275 1125)(-6275 1075);
WIRE 16 -1 (-6450 1075)(-6275 1075);
WIRE 16 -1 (-6275 1175)(-6275 1125);
WIRE 16 -1 (-6450 1125)(-6275 1125);
WIRE 16 -1 (-6275 1225)(-6275 1175);
WIRE 16 -1 (-6450 1175)(-6275 1175);
WIRE 16 -1 (-6275 1275)(-6275 1225);
WIRE 16 -1 (-6450 1225)(-6275 1225);
WIRE 16 -1 (-6275 1325)(-6275 1275);
WIRE 16 -1 (-6450 1275)(-6275 1275);
WIRE 16 -1 (-6275 1375)(-6275 1325);
WIRE 16 -1 (-6450 1325)(-6275 1325);
WIRE 16 -1 (-6275 1425)(-6275 1375);
WIRE 16 -1 (-6450 1375)(-6275 1375);
WIRE 16 -1 (-6275 1475)(-6275 1425);
WIRE 16 -1 (-6450 1425)(-6275 1425);
WIRE 16 -1 (-6275 1525)(-6275 1475);
WIRE 16 -1 (-6450 1475)(-6275 1475);
WIRE 16 -1 (-6275 1575)(-6275 1525);
WIRE 16 -1 (-6450 1525)(-6275 1525);
WIRE 16 -1 (-6275 1625)(-6275 1575);
WIRE 16 -1 (-6450 1575)(-6275 1575);
WIRE 16 -1 (-6275 1675)(-6275 1625);
WIRE 16 -1 (-6450 1625)(-6275 1625);
WIRE 16 -1 (-6275 1725)(-6275 1675);
WIRE 16 -1 (-6450 1675)(-6275 1675);
WIRE 16 -1 (-6275 1775)(-6275 1725);
WIRE 16 -1 (-6450 1725)(-6275 1725);
WIRE 16 -1 (-6275 1825)(-6275 1775);
WIRE 16 -1 (-6450 1775)(-6275 1775);
WIRE 16 -1 (-6275 1875)(-6275 1825);
WIRE 16 -1 (-6450 1825)(-6275 1825);
WIRE 16 -1 (-6275 1925)(-6275 1875);
WIRE 16 -1 (-6450 1875)(-6275 1875);
WIRE 16 -1 (-6275 1975)(-6275 1925);
WIRE 16 -1 (-6450 1925)(-6275 1925);
WIRE 16 -1 (-6275 2025)(-6275 1975);
WIRE 16 -1 (-6450 1975)(-6275 1975);
WIRE 16 -1 (-6275 2075)(-6275 2025);
WIRE 16 -1 (-6450 2025)(-6275 2025);
WIRE 16 -1 (-6275 2125)(-6275 2075);
WIRE 16 -1 (-6450 2075)(-6275 2075);
WIRE 16 -1 (-6275 2175)(-6275 2125);
WIRE 16 -1 (-6450 2125)(-6275 2125);
WIRE 16 -1 (-6275 2225)(-6275 2175);
WIRE 16 -1 (-6450 2175)(-6275 2175);
WIRE 16 -1 (-6275 2275)(-6275 2225);
WIRE 16 -1 (-6450 2225)(-6275 2225);
WIRE 16 -1 (-6275 2325)(-6275 2275);
WIRE 16 -1 (-6450 2275)(-6275 2275);
WIRE 16 -1 (-6275 2375)(-6275 2325);
WIRE 16 -1 (-6450 2325)(-6275 2325);
WIRE 16 -1 (-6275 2425)(-6275 2375);
WIRE 16 -1 (-6450 2375)(-6275 2375);
WIRE 16 -1 (-6275 2475)(-6275 2425);
WIRE 16 -1 (-6450 2425)(-6275 2425);
WIRE 16 -1 (-6275 2525)(-6275 2475);
WIRE 16 -1 (-6450 2475)(-6275 2475);
WIRE 16 -1 (-6275 2575)(-6275 2525);
WIRE 16 -1 (-6450 2525)(-6275 2525);
WIRE 16 -1 (-6275 2625)(-6275 2575);
WIRE 16 -1 (-6450 2575)(-6275 2575);
WIRE 16 -1 (-6275 2675)(-6275 2625);
WIRE 16 -1 (-6450 2625)(-6275 2625);
WIRE 16 -1 (-6275 2725)(-6275 2675);
WIRE 16 -1 (-6450 2675)(-6275 2675);
WIRE 16 -1 (-6275 2775)(-6275 2725);
WIRE 16 -1 (-6450 2725)(-6275 2725);
WIRE 16 -1 (-6275 2825)(-6275 2775);
WIRE 16 -1 (-6450 2775)(-6275 2775);
WIRE 16 -1 (-6275 2875)(-6275 2825);
WIRE 16 -1 (-6450 2825)(-6275 2825);
WIRE 16 -1 (-6275 2925)(-6275 2875);
WIRE 16 -1 (-6450 2875)(-6275 2875);
WIRE 16 -1 (-6275 2975)(-6275 2925);
WIRE 16 -1 (-6450 2925)(-6275 2925);
WIRE 16 -1 (-6275 3025)(-6275 2975);
WIRE 16 -1 (-6450 2975)(-6275 2975);
WIRE 16 -1 (-6275 3075)(-6275 3025);
WIRE 16 -1 (-6450 3025)(-6275 3025);
WIRE 16 -1 (-6275 3125)(-6275 3075);
WIRE 16 -1 (-6450 3075)(-6275 3075);
WIRE 16 -1 (-6275 3175)(-6275 3125);
WIRE 16 -1 (-6450 3125)(-6275 3125);
WIRE 16 -1 (-6275 3225)(-6275 3175);
WIRE 16 -1 (-6450 3175)(-6275 3175);
WIRE 16 -1 (-6275 3275)(-6275 3225);
WIRE 16 -1 (-6450 3225)(-6275 3225);
WIRE 16 -1 (-6275 3325)(-6275 3275);
WIRE 16 -1 (-6450 3275)(-6275 3275);
WIRE 16 -1 (-6275 3375)(-6275 3325);
WIRE 16 -1 (-6450 3325)(-6275 3325);
WIRE 16 -1 (-6275 3425)(-6275 3375);
WIRE 16 -1 (-6450 3375)(-6275 3375);
WIRE 16 -1 (-6275 3475)(-6275 3425);
WIRE 16 -1 (-6450 3425)(-6275 3425);
WIRE 16 -1 (-6275 3525)(-6275 3475);
WIRE 16 -1 (-6450 3475)(-6275 3475);
WIRE 16 -1 (-6275 3575)(-6275 3525);
WIRE 16 -1 (-6450 3525)(-6275 3525);
WIRE 16 -1 (-6275 3625)(-6275 3575);
WIRE 16 -1 (-6450 3575)(-6275 3575);
WIRE 16 -1 (-6275 3675)(-6275 3625);
WIRE 16 -1 (-6450 3625)(-6275 3625);
WIRE 16 -1 (-6275 3725)(-6275 3675);
WIRE 16 -1 (-6450 3675)(-6275 3675);
WIRE 16 -1 (-6275 3775)(-6275 3725);
WIRE 16 -1 (-6450 3725)(-6275 3725);
WIRE 16 -1 (-6275 3825)(-6275 3775);
WIRE 16 -1 (-6450 3775)(-6275 3775);
WIRE 16 -1 (-6275 3875)(-6275 3825);
WIRE 16 -1 (-6450 3825)(-6275 3825);
WIRE 16 -1 (-6275 3925)(-6275 3875);
WIRE 16 -1 (-6450 3875)(-6275 3875);
WIRE 16 -1 (-6275 3975)(-6275 3925);
WIRE 16 -1 (-6450 3925)(-6275 3925);
WIRE 16 -1 (-6275 4025)(-6275 3975);
WIRE 16 -1 (-6450 3975)(-6275 3975);
WIRE 16 -1 (-6275 4075)(-6275 4025);
WIRE 16 -1 (-6450 4025)(-6275 4025);
WIRE 16 -1 (-6275 4125)(-6275 4075);
WIRE 16 -1 (-6450 4075)(-6275 4075);
WIRE 16 -1 (-6275 4175)(-6275 4125);
WIRE 16 -1 (-6450 4125)(-6275 4125);
WIRE 16 -1 (-6275 4225)(-6275 4175);
WIRE 16 -1 (-6450 4175)(-6275 4175);
WIRE 16 -1 (-6275 4275)(-6275 4225);
WIRE 16 -1 (-6450 4225)(-6275 4225);
WIRE 16 -1 (-6275 4325)(-6275 4275);
WIRE 16 -1 (-6450 4275)(-6275 4275);
WIRE 16 -1 (-6275 4375)(-6275 4325);
WIRE 16 -1 (-6450 4325)(-6275 4325);
WIRE 16 -1 (-6275 4425)(-6275 4375);
WIRE 16 -1 (-6450 4375)(-6275 4375);
WIRE 16 -1 (-6275 4475)(-6275 4425);
WIRE 16 -1 (-6450 4425)(-6275 4425);
WIRE 16 -1 (-6275 4525)(-6275 4475);
WIRE 16 -1 (-6450 4475)(-6275 4475);
WIRE 16 -1 (-6275 4575)(-6275 4525);
WIRE 16 -1 (-6450 4525)(-6275 4525);
WIRE 16 -1 (-6450 4575)(-6275 4575);
WIRE 16 -1 (-4450 625)(-4450 500);
WIRE 16 -1 (-4450 675)(-4450 625);
WIRE 16 -1 (-4625 625)(-4450 625);
WIRE 16 -1 (-4450 725)(-4450 675);
WIRE 16 -1 (-4625 675)(-4450 675);
WIRE 16 -1 (-4450 775)(-4450 725);
WIRE 16 -1 (-4625 725)(-4450 725);
WIRE 16 -1 (-4450 825)(-4450 775);
WIRE 16 -1 (-4625 775)(-4450 775);
WIRE 16 -1 (-4450 875)(-4450 825);
WIRE 16 -1 (-4625 825)(-4450 825);
WIRE 16 -1 (-4450 925)(-4450 875);
WIRE 16 -1 (-4625 875)(-4450 875);
WIRE 16 -1 (-4450 975)(-4450 925);
WIRE 16 -1 (-4625 925)(-4450 925);
WIRE 16 -1 (-4450 1025)(-4450 975);
WIRE 16 -1 (-4625 975)(-4450 975);
WIRE 16 -1 (-4450 1075)(-4450 1025);
WIRE 16 -1 (-4625 1025)(-4450 1025);
WIRE 16 -1 (-4450 1125)(-4450 1075);
WIRE 16 -1 (-4625 1075)(-4450 1075);
WIRE 16 -1 (-4450 1175)(-4450 1125);
WIRE 16 -1 (-4625 1125)(-4450 1125);
WIRE 16 -1 (-4450 1225)(-4450 1175);
WIRE 16 -1 (-4625 1175)(-4450 1175);
WIRE 16 -1 (-4450 1275)(-4450 1225);
WIRE 16 -1 (-4625 1225)(-4450 1225);
WIRE 16 -1 (-4450 1325)(-4450 1275);
WIRE 16 -1 (-4625 1275)(-4450 1275);
WIRE 16 -1 (-4450 1375)(-4450 1325);
WIRE 16 -1 (-4625 1325)(-4450 1325);
WIRE 16 -1 (-4450 1425)(-4450 1375);
WIRE 16 -1 (-4625 1375)(-4450 1375);
WIRE 16 -1 (-4450 1475)(-4450 1425);
WIRE 16 -1 (-4625 1425)(-4450 1425);
WIRE 16 -1 (-4450 1525)(-4450 1475);
WIRE 16 -1 (-4625 1475)(-4450 1475);
WIRE 16 -1 (-4450 1575)(-4450 1525);
WIRE 16 -1 (-4625 1525)(-4450 1525);
WIRE 16 -1 (-4450 1625)(-4450 1575);
WIRE 16 -1 (-4625 1575)(-4450 1575);
WIRE 16 -1 (-4450 1675)(-4450 1625);
WIRE 16 -1 (-4625 1625)(-4450 1625);
WIRE 16 -1 (-4450 1725)(-4450 1675);
WIRE 16 -1 (-4625 1675)(-4450 1675);
WIRE 16 -1 (-4450 1775)(-4450 1725);
WIRE 16 -1 (-4625 1725)(-4450 1725);
WIRE 16 -1 (-4450 1825)(-4450 1775);
WIRE 16 -1 (-4625 1775)(-4450 1775);
WIRE 16 -1 (-4450 1875)(-4450 1825);
WIRE 16 -1 (-4625 1825)(-4450 1825);
WIRE 16 -1 (-4450 1925)(-4450 1875);
WIRE 16 -1 (-4625 1875)(-4450 1875);
WIRE 16 -1 (-4450 1975)(-4450 1925);
WIRE 16 -1 (-4625 1925)(-4450 1925);
WIRE 16 -1 (-4450 2025)(-4450 1975);
WIRE 16 -1 (-4625 1975)(-4450 1975);
WIRE 16 -1 (-4450 2075)(-4450 2025);
WIRE 16 -1 (-4625 2025)(-4450 2025);
WIRE 16 -1 (-4450 2125)(-4450 2075);
WIRE 16 -1 (-4625 2075)(-4450 2075);
WIRE 16 -1 (-4450 2175)(-4450 2125);
WIRE 16 -1 (-4625 2125)(-4450 2125);
WIRE 16 -1 (-4450 2225)(-4450 2175);
WIRE 16 -1 (-4625 2175)(-4450 2175);
WIRE 16 -1 (-4450 2275)(-4450 2225);
WIRE 16 -1 (-4625 2225)(-4450 2225);
WIRE 16 -1 (-4450 2325)(-4450 2275);
WIRE 16 -1 (-4625 2275)(-4450 2275);
WIRE 16 -1 (-4450 2375)(-4450 2325);
WIRE 16 -1 (-4625 2325)(-4450 2325);
WIRE 16 -1 (-4450 2425)(-4450 2375);
WIRE 16 -1 (-4625 2375)(-4450 2375);
WIRE 16 -1 (-4450 2475)(-4450 2425);
WIRE 16 -1 (-4625 2425)(-4450 2425);
WIRE 16 -1 (-4450 2525)(-4450 2475);
WIRE 16 -1 (-4625 2475)(-4450 2475);
WIRE 16 -1 (-4450 2575)(-4450 2525);
WIRE 16 -1 (-4625 2525)(-4450 2525);
WIRE 16 -1 (-4450 2625)(-4450 2575);
WIRE 16 -1 (-4625 2575)(-4450 2575);
WIRE 16 -1 (-4450 2675)(-4450 2625);
WIRE 16 -1 (-4625 2625)(-4450 2625);
WIRE 16 -1 (-4450 2725)(-4450 2675);
WIRE 16 -1 (-4625 2675)(-4450 2675);
WIRE 16 -1 (-4450 2775)(-4450 2725);
WIRE 16 -1 (-4625 2725)(-4450 2725);
WIRE 16 -1 (-4450 2825)(-4450 2775);
WIRE 16 -1 (-4625 2775)(-4450 2775);
WIRE 16 -1 (-4450 2875)(-4450 2825);
WIRE 16 -1 (-4625 2825)(-4450 2825);
WIRE 16 -1 (-4450 2925)(-4450 2875);
WIRE 16 -1 (-4625 2875)(-4450 2875);
WIRE 16 -1 (-4450 2975)(-4450 2925);
WIRE 16 -1 (-4625 2925)(-4450 2925);
WIRE 16 -1 (-4450 3025)(-4450 2975);
WIRE 16 -1 (-4625 2975)(-4450 2975);
WIRE 16 -1 (-4450 3075)(-4450 3025);
WIRE 16 -1 (-4625 3025)(-4450 3025);
WIRE 16 -1 (-4450 3125)(-4450 3075);
WIRE 16 -1 (-4625 3075)(-4450 3075);
WIRE 16 -1 (-4450 3175)(-4450 3125);
WIRE 16 -1 (-4625 3125)(-4450 3125);
WIRE 16 -1 (-4450 3225)(-4450 3175);
WIRE 16 -1 (-4625 3175)(-4450 3175);
WIRE 16 -1 (-4450 3275)(-4450 3225);
WIRE 16 -1 (-4625 3225)(-4450 3225);
WIRE 16 -1 (-4450 3325)(-4450 3275);
WIRE 16 -1 (-4625 3275)(-4450 3275);
WIRE 16 -1 (-4450 3375)(-4450 3325);
WIRE 16 -1 (-4625 3325)(-4450 3325);
WIRE 16 -1 (-4450 3425)(-4450 3375);
WIRE 16 -1 (-4625 3375)(-4450 3375);
WIRE 16 -1 (-4450 3475)(-4450 3425);
WIRE 16 -1 (-4625 3425)(-4450 3425);
WIRE 16 -1 (-4450 3525)(-4450 3475);
WIRE 16 -1 (-4625 3475)(-4450 3475);
WIRE 16 -1 (-4450 3575)(-4450 3525);
WIRE 16 -1 (-4625 3525)(-4450 3525);
WIRE 16 -1 (-4450 3625)(-4450 3575);
WIRE 16 -1 (-4625 3575)(-4450 3575);
WIRE 16 -1 (-4450 3675)(-4450 3625);
WIRE 16 -1 (-4625 3625)(-4450 3625);
WIRE 16 -1 (-4450 3725)(-4450 3675);
WIRE 16 -1 (-4625 3675)(-4450 3675);
WIRE 16 -1 (-4450 3775)(-4450 3725);
WIRE 16 -1 (-4625 3725)(-4450 3725);
WIRE 16 -1 (-4450 3825)(-4450 3775);
WIRE 16 -1 (-4625 3775)(-4450 3775);
WIRE 16 -1 (-4450 3875)(-4450 3825);
WIRE 16 -1 (-4625 3825)(-4450 3825);
WIRE 16 -1 (-4450 3925)(-4450 3875);
WIRE 16 -1 (-4625 3875)(-4450 3875);
WIRE 16 -1 (-4450 3975)(-4450 3925);
WIRE 16 -1 (-4625 3925)(-4450 3925);
WIRE 16 -1 (-4450 4025)(-4450 3975);
WIRE 16 -1 (-4625 3975)(-4450 3975);
WIRE 16 -1 (-4450 4075)(-4450 4025);
WIRE 16 -1 (-4625 4025)(-4450 4025);
WIRE 16 -1 (-4450 4125)(-4450 4075);
WIRE 16 -1 (-4625 4075)(-4450 4075);
WIRE 16 -1 (-4450 4175)(-4450 4125);
WIRE 16 -1 (-4625 4125)(-4450 4125);
WIRE 16 -1 (-4450 4225)(-4450 4175);
WIRE 16 -1 (-4625 4175)(-4450 4175);
WIRE 16 -1 (-4450 4275)(-4450 4225);
WIRE 16 -1 (-4625 4225)(-4450 4225);
WIRE 16 -1 (-4450 4325)(-4450 4275);
WIRE 16 -1 (-4625 4275)(-4450 4275);
WIRE 16 -1 (-4450 4375)(-4450 4325);
WIRE 16 -1 (-4625 4325)(-4450 4325);
WIRE 16 -1 (-4450 4425)(-4450 4375);
WIRE 16 -1 (-4625 4375)(-4450 4375);
WIRE 16 -1 (-4450 4475)(-4450 4425);
WIRE 16 -1 (-4625 4425)(-4450 4425);
WIRE 16 -1 (-4450 4525)(-4450 4475);
WIRE 16 -1 (-4625 4475)(-4450 4475);
WIRE 16 -1 (-4450 4575)(-4450 4525);
WIRE 16 -1 (-4625 4525)(-4450 4525);
WIRE 16 -1 (-4450 4575)(-4625 4575);
WIRE 16 -1 (-4150 625)(-4150 500);
WIRE 16 -1 (-4150 675)(-4150 625);
WIRE 16 -1 (-4150 625)(-4000 625);
WIRE 16 -1 (-4150 725)(-4150 675);
WIRE 16 -1 (-4000 675)(-4150 675);
WIRE 16 -1 (-4150 775)(-4150 725);
WIRE 16 -1 (-4000 725)(-4150 725);
WIRE 16 -1 (-4150 825)(-4150 775);
WIRE 16 -1 (-4000 775)(-4150 775);
WIRE 16 -1 (-4150 875)(-4150 825);
WIRE 16 -1 (-4000 825)(-4150 825);
WIRE 16 -1 (-4150 925)(-4150 875);
WIRE 16 -1 (-4000 875)(-4150 875);
WIRE 16 -1 (-4150 975)(-4150 925);
WIRE 16 -1 (-4000 925)(-4150 925);
WIRE 16 -1 (-4150 1025)(-4150 975);
WIRE 16 -1 (-4000 975)(-4150 975);
WIRE 16 -1 (-4150 1075)(-4150 1025);
WIRE 16 -1 (-4000 1025)(-4150 1025);
WIRE 16 -1 (-4150 1125)(-4150 1075);
WIRE 16 -1 (-4000 1075)(-4150 1075);
WIRE 16 -1 (-4150 1175)(-4150 1125);
WIRE 16 -1 (-4000 1125)(-4150 1125);
WIRE 16 -1 (-4150 1225)(-4150 1175);
WIRE 16 -1 (-4000 1175)(-4150 1175);
WIRE 16 -1 (-4150 1275)(-4150 1225);
WIRE 16 -1 (-4000 1225)(-4150 1225);
WIRE 16 -1 (-4150 1325)(-4150 1275);
WIRE 16 -1 (-4000 1275)(-4150 1275);
WIRE 16 -1 (-4150 1375)(-4150 1325);
WIRE 16 -1 (-4000 1325)(-4150 1325);
WIRE 16 -1 (-4150 1425)(-4150 1375);
WIRE 16 -1 (-4000 1375)(-4150 1375);
WIRE 16 -1 (-4150 1475)(-4150 1425);
WIRE 16 -1 (-4000 1425)(-4150 1425);
WIRE 16 -1 (-4150 1525)(-4150 1475);
WIRE 16 -1 (-4000 1475)(-4150 1475);
WIRE 16 -1 (-4150 1575)(-4150 1525);
WIRE 16 -1 (-4000 1525)(-4150 1525);
WIRE 16 -1 (-4150 1625)(-4150 1575);
WIRE 16 -1 (-4000 1575)(-4150 1575);
WIRE 16 -1 (-4150 1675)(-4150 1625);
WIRE 16 -1 (-4000 1625)(-4150 1625);
WIRE 16 -1 (-4150 1725)(-4150 1675);
WIRE 16 -1 (-4000 1675)(-4150 1675);
WIRE 16 -1 (-4150 1775)(-4150 1725);
WIRE 16 -1 (-4000 1725)(-4150 1725);
WIRE 16 -1 (-4150 1825)(-4150 1775);
WIRE 16 -1 (-4000 1775)(-4150 1775);
WIRE 16 -1 (-4150 1875)(-4150 1825);
WIRE 16 -1 (-4000 1825)(-4150 1825);
WIRE 16 -1 (-4150 1925)(-4150 1875);
WIRE 16 -1 (-4000 1875)(-4150 1875);
WIRE 16 -1 (-4150 1975)(-4150 1925);
WIRE 16 -1 (-4000 1925)(-4150 1925);
WIRE 16 -1 (-4150 2025)(-4150 1975);
WIRE 16 -1 (-4000 1975)(-4150 1975);
WIRE 16 -1 (-4150 2075)(-4150 2025);
WIRE 16 -1 (-4000 2025)(-4150 2025);
WIRE 16 -1 (-4150 2125)(-4150 2075);
WIRE 16 -1 (-4000 2075)(-4150 2075);
WIRE 16 -1 (-4150 2175)(-4150 2125);
WIRE 16 -1 (-4000 2125)(-4150 2125);
WIRE 16 -1 (-4150 2225)(-4150 2175);
WIRE 16 -1 (-4000 2175)(-4150 2175);
WIRE 16 -1 (-4150 2275)(-4150 2225);
WIRE 16 -1 (-4000 2225)(-4150 2225);
WIRE 16 -1 (-4150 2325)(-4150 2275);
WIRE 16 -1 (-4000 2275)(-4150 2275);
WIRE 16 -1 (-4150 2375)(-4150 2325);
WIRE 16 -1 (-4000 2325)(-4150 2325);
WIRE 16 -1 (-4150 2425)(-4150 2375);
WIRE 16 -1 (-4000 2375)(-4150 2375);
WIRE 16 -1 (-4150 2475)(-4150 2425);
WIRE 16 -1 (-4000 2425)(-4150 2425);
WIRE 16 -1 (-4150 2525)(-4150 2475);
WIRE 16 -1 (-4000 2475)(-4150 2475);
WIRE 16 -1 (-4150 2575)(-4150 2525);
WIRE 16 -1 (-4000 2525)(-4150 2525);
WIRE 16 -1 (-4150 2625)(-4150 2575);
WIRE 16 -1 (-4000 2575)(-4150 2575);
WIRE 16 -1 (-4150 2675)(-4150 2625);
WIRE 16 -1 (-4000 2625)(-4150 2625);
WIRE 16 -1 (-4150 2725)(-4150 2675);
WIRE 16 -1 (-4000 2675)(-4150 2675);
WIRE 16 -1 (-4150 2775)(-4150 2725);
WIRE 16 -1 (-4000 2725)(-4150 2725);
WIRE 16 -1 (-4150 2825)(-4150 2775);
WIRE 16 -1 (-4000 2775)(-4150 2775);
WIRE 16 -1 (-4150 2875)(-4150 2825);
WIRE 16 -1 (-4000 2825)(-4150 2825);
WIRE 16 -1 (-4150 2925)(-4150 2875);
WIRE 16 -1 (-4000 2875)(-4150 2875);
WIRE 16 -1 (-4150 2975)(-4150 2925);
WIRE 16 -1 (-4000 2925)(-4150 2925);
WIRE 16 -1 (-4150 3025)(-4150 2975);
WIRE 16 -1 (-4000 2975)(-4150 2975);
WIRE 16 -1 (-4150 3075)(-4150 3025);
WIRE 16 -1 (-4000 3025)(-4150 3025);
WIRE 16 -1 (-4150 3125)(-4150 3075);
WIRE 16 -1 (-4000 3075)(-4150 3075);
WIRE 16 -1 (-4150 3175)(-4150 3125);
WIRE 16 -1 (-4000 3125)(-4150 3125);
WIRE 16 -1 (-4150 3225)(-4150 3175);
WIRE 16 -1 (-4000 3175)(-4150 3175);
WIRE 16 -1 (-4150 3275)(-4150 3225);
WIRE 16 -1 (-4000 3225)(-4150 3225);
WIRE 16 -1 (-4150 3325)(-4150 3275);
WIRE 16 -1 (-4000 3275)(-4150 3275);
WIRE 16 -1 (-4150 3375)(-4150 3325);
WIRE 16 -1 (-4000 3325)(-4150 3325);
WIRE 16 -1 (-4150 3425)(-4150 3375);
WIRE 16 -1 (-4000 3375)(-4150 3375);
WIRE 16 -1 (-4150 3475)(-4150 3425);
WIRE 16 -1 (-4000 3425)(-4150 3425);
WIRE 16 -1 (-4150 3525)(-4150 3475);
WIRE 16 -1 (-4000 3475)(-4150 3475);
WIRE 16 -1 (-4150 3575)(-4150 3525);
WIRE 16 -1 (-4000 3525)(-4150 3525);
WIRE 16 -1 (-4150 3625)(-4150 3575);
WIRE 16 -1 (-4000 3575)(-4150 3575);
WIRE 16 -1 (-4150 3675)(-4150 3625);
WIRE 16 -1 (-4000 3625)(-4150 3625);
WIRE 16 -1 (-4150 3725)(-4150 3675);
WIRE 16 -1 (-4000 3675)(-4150 3675);
WIRE 16 -1 (-4150 3775)(-4150 3725);
WIRE 16 -1 (-4000 3725)(-4150 3725);
WIRE 16 -1 (-4150 3825)(-4150 3775);
WIRE 16 -1 (-4000 3775)(-4150 3775);
WIRE 16 -1 (-4150 3875)(-4150 3825);
WIRE 16 -1 (-4000 3825)(-4150 3825);
WIRE 16 -1 (-4150 3925)(-4150 3875);
WIRE 16 -1 (-4000 3875)(-4150 3875);
WIRE 16 -1 (-4150 3975)(-4150 3925);
WIRE 16 -1 (-4000 3925)(-4150 3925);
WIRE 16 -1 (-4150 4025)(-4150 3975);
WIRE 16 -1 (-4000 3975)(-4150 3975);
WIRE 16 -1 (-4150 4075)(-4150 4025);
WIRE 16 -1 (-4000 4025)(-4150 4025);
WIRE 16 -1 (-4150 4125)(-4150 4075);
WIRE 16 -1 (-4000 4075)(-4150 4075);
WIRE 16 -1 (-4150 4175)(-4150 4125);
WIRE 16 -1 (-4000 4125)(-4150 4125);
WIRE 16 -1 (-4150 4225)(-4150 4175);
WIRE 16 -1 (-4000 4175)(-4150 4175);
WIRE 16 -1 (-4150 4275)(-4150 4225);
WIRE 16 -1 (-4000 4225)(-4150 4225);
WIRE 16 -1 (-4150 4325)(-4150 4275);
WIRE 16 -1 (-4000 4275)(-4150 4275);
WIRE 16 -1 (-4150 4375)(-4150 4325);
WIRE 16 -1 (-4000 4325)(-4150 4325);
WIRE 16 -1 (-4150 4425)(-4150 4375);
WIRE 16 -1 (-4000 4375)(-4150 4375);
WIRE 16 -1 (-4150 4475)(-4150 4425);
WIRE 16 -1 (-4000 4425)(-4150 4425);
WIRE 16 -1 (-4150 4525)(-4150 4475);
WIRE 16 -1 (-4000 4475)(-4150 4475);
WIRE 16 -1 (-4150 4575)(-4150 4525);
WIRE 16 -1 (-4000 4525)(-4150 4525);
WIRE 16 -1 (-4150 4575)(-4000 4575);
DOT 1 (-4450 3775);
DOT 1 (-7800 4325);
DOT 1 (-4150 3925);
DOT 1 (-775 1125);
DOT 1 (-6275 3625);
DOT 1 (-6275 4075);
DOT 1 (-5975 4375);
DOT 1 (-5975 4425);
DOT 1 (-5975 3875);
DOT 1 (-5975 3725);
DOT 1 (-5975 3575);
DOT 1 (-4150 1375);
DOT 1 (-5975 4475);
DOT 1 (-5975 4325);
DOT 1 (-5975 4275);
DOT 1 (-6275 4325);
DOT 1 (-6275 3975);
DOT 1 (-6275 4175);
DOT 1 (-6275 3175);
DOT 1 (-6275 2625);
DOT 1 (-6275 2125);
DOT 1 (-6275 1625);
DOT 1 (-5975 675);
DOT 1 (-6275 875);
DOT 1 (-6275 2825);
DOT 1 (-4150 3625);
DOT 1 (-6275 3275);
DOT 1 (-2325 2375);
DOT 1 (-775 1625);
DOT 1 (-2625 1525);
DOT 1 (-4450 1725);
DOT 1 (-4450 1675);
DOT 1 (-5975 1675);
DOT 1 (-4150 2575);
DOT 1 (-4150 2625);
DOT 1 (-4150 2675);
DOT 1 (-4150 2725);
DOT 1 (-5975 3275);
DOT 1 (-5975 2675);
DOT 1 (-5975 2475);
DOT 1 (-5975 2275);
DOT 1 (-5975 2075);
DOT 1 (-5975 2025);
DOT 1 (-5975 1725);
DOT 1 (-5975 1775);
DOT 1 (-5975 1925);
DOT 1 (-6275 4525);
DOT 1 (-4450 4225);
DOT 1 (-4150 1325);
DOT 1 (-2625 1925);
DOT 1 (-6275 1275);
DOT 1 (-4450 3675);
DOT 1 (-5975 3525);
DOT 1 (-4450 3725);
DOT 1 (-2325 625);
DOT 1 (-2325 675);
DOT 1 (-2325 725);
DOT 1 (-2325 775);
DOT 1 (-2625 1625);
DOT 1 (-2625 1675);
DOT 1 (-2325 825);
DOT 1 (-2325 875);
DOT 1 (-2325 925);
DOT 1 (-2625 1425);
DOT 1 (-4150 2425);
DOT 1 (-4150 2375);
DOT 1 (-2625 975);
DOT 1 (-2625 875);
DOT 1 (-2625 825);
DOT 1 (-2625 775);
DOT 1 (-2625 725);
DOT 1 (-775 625);
DOT 1 (-775 675);
DOT 1 (-775 725);
DOT 1 (-775 775);
DOT 1 (-775 875);
DOT 1 (-775 825);
DOT 1 (-775 975);
DOT 1 (-775 925);
DOT 1 (-775 1025);
DOT 1 (-775 1075);
DOT 1 (-775 1225);
DOT 1 (-775 1275);
DOT 1 (-775 1175);
DOT 1 (-775 1325);
DOT 1 (-775 1375);
DOT 1 (-775 1475);
DOT 1 (-775 1525);
DOT 1 (-775 1425);
DOT 1 (-775 1575);
DOT 1 (-775 1675);
DOT 1 (-775 1775);
DOT 1 (-775 1725);
DOT 1 (-775 1875);
DOT 1 (-775 1825);
DOT 1 (-775 1925);
DOT 1 (-775 2025);
DOT 1 (-775 1975);
DOT 1 (-775 2175);
DOT 1 (-775 2125);
DOT 1 (-775 2075);
DOT 1 (-775 2225);
DOT 1 (-775 2275);
DOT 1 (-775 2425);
DOT 1 (-775 2375);
DOT 1 (-775 2325);
DOT 1 (-775 2475);
DOT 1 (-775 2525);
DOT 1 (-775 2675);
DOT 1 (-775 2625);
DOT 1 (-775 2575);
DOT 1 (-775 2725);
DOT 1 (-775 2775);
DOT 1 (-775 2825);
DOT 1 (-775 2925);
DOT 1 (-775 2875);
DOT 1 (-775 3025);
DOT 1 (-775 2975);
DOT 1 (-775 3075);
DOT 1 (-775 3175);
DOT 1 (-775 3125);
DOT 1 (-775 3275);
DOT 1 (-775 3325);
DOT 1 (-775 3225);
DOT 1 (-775 3425);
DOT 1 (-775 3375);
DOT 1 (-775 3525);
DOT 1 (-775 3575);
DOT 1 (-775 3475);
DOT 1 (-775 3675);
DOT 1 (-775 3725);
DOT 1 (-775 3825);
DOT 1 (-775 3775);
DOT 1 (-775 3925);
DOT 1 (-775 3875);
DOT 1 (-775 3975);
DOT 1 (-775 4075);
DOT 1 (-775 4025);
DOT 1 (-775 4175);
DOT 1 (-775 4125);
DOT 1 (-775 4225);
DOT 1 (-775 4325);
DOT 1 (-775 4275);
DOT 1 (-775 4425);
DOT 1 (-775 4475);
DOT 1 (-775 4375);
DOT 1 (-775 4525);
DOT 1 (-2625 4525);
DOT 1 (-2625 4375);
DOT 1 (-2625 4475);
DOT 1 (-2625 4425);
DOT 1 (-2625 4275);
DOT 1 (-2625 4325);
DOT 1 (-2625 4225);
DOT 1 (-2625 4125);
DOT 1 (-2625 4175);
DOT 1 (-2625 4025);
DOT 1 (-2625 4075);
DOT 1 (-2625 3975);
DOT 1 (-2625 3875);
DOT 1 (-2625 3925);
DOT 1 (-2625 3775);
DOT 1 (-2625 3825);
DOT 1 (-2625 3725);
DOT 1 (-2625 3625);
DOT 1 (-2625 3675);
DOT 1 (-2625 3475);
DOT 1 (-2625 3575);
DOT 1 (-2625 3525);
DOT 1 (-2625 3375);
DOT 1 (-2625 3425);
DOT 1 (-2625 3225);
DOT 1 (-2625 3325);
DOT 1 (-2625 3275);
DOT 1 (-2625 3125);
DOT 1 (-2625 3175);
DOT 1 (-2625 3075);
DOT 1 (-2625 2975);
DOT 1 (-2625 3025);
DOT 1 (-2625 2875);
DOT 1 (-2625 2925);
DOT 1 (-2625 2825);
DOT 1 (-2625 2775);
DOT 1 (-2625 2725);
DOT 1 (-2625 2575);
DOT 1 (-2625 2625);
DOT 1 (-2625 2675);
DOT 1 (-2625 2525);
DOT 1 (-2625 2475);
DOT 1 (-2625 2325);
DOT 1 (-2625 2375);
DOT 1 (-2625 2425);
DOT 1 (-2625 2275);
DOT 1 (-2625 2225);
DOT 1 (-2625 2075);
DOT 1 (-2625 2125);
DOT 1 (-2625 2175);
DOT 1 (-2625 1975);
DOT 1 (-2625 2025);
DOT 1 (-2625 1825);
DOT 1 (-2625 1875);
DOT 1 (-2625 1725);
DOT 1 (-2625 1775);
DOT 1 (-2625 1575);
DOT 1 (-2625 1475);
DOT 1 (-2625 1375);
DOT 1 (-2625 1325);
DOT 1 (-2625 1175);
DOT 1 (-2625 1275);
DOT 1 (-2625 1225);
DOT 1 (-2625 1075);
DOT 1 (-2625 1125);
DOT 1 (-2625 1025);
DOT 1 (-2625 925);
DOT 1 (-2625 675);
DOT 1 (-2625 625);
DOT 1 (-2325 1325);
DOT 1 (-2325 1675);
DOT 1 (-4450 1375);
DOT 1 (-2325 4525);
DOT 1 (-2325 4475);
DOT 1 (-2325 4375);
DOT 1 (-2325 4425);
DOT 1 (-2325 4325);
DOT 1 (-2325 4275);
DOT 1 (-2325 4225);
DOT 1 (-2325 4175);
DOT 1 (-2325 4125);
DOT 1 (-2325 4075);
DOT 1 (-2325 4025);
DOT 1 (-2325 3975);
DOT 1 (-2325 3925);
DOT 1 (-2325 3875);
DOT 1 (-2325 3825);
DOT 1 (-2325 3725);
DOT 1 (-2325 3775);
DOT 1 (-2325 3675);
DOT 1 (-2325 3625);
DOT 1 (-2325 3575);
DOT 1 (-2325 3475);
DOT 1 (-2325 3525);
DOT 1 (-2325 3425);
DOT 1 (-2325 3375);
DOT 1 (-2325 3325);
DOT 1 (-2325 3225);
DOT 1 (-2325 3075);
DOT 1 (-2325 3125);
DOT 1 (-2325 3175);
DOT 1 (-2325 3025);
DOT 1 (-2325 2975);
DOT 1 (-2325 2925);
DOT 1 (-2325 2825);
DOT 1 (-2325 2875);
DOT 1 (-2325 2775);
DOT 1 (-2325 2725);
DOT 1 (-2325 2675);
DOT 1 (-2325 2575);
DOT 1 (-2325 2625);
DOT 1 (-2325 2525);
DOT 1 (-2325 2475);
DOT 1 (-2325 2425);
DOT 1 (-2325 2325);
DOT 1 (-2325 2275);
DOT 1 (-2325 2225);
DOT 1 (-2325 2175);
DOT 1 (-2325 2125);
DOT 1 (-2325 2075);
DOT 1 (-2325 2025);
DOT 1 (-2325 1925);
DOT 1 (-2325 1975);
DOT 1 (-2325 1875);
DOT 1 (-2325 1825);
DOT 1 (-2325 1775);
DOT 1 (-2325 1725);
DOT 1 (-2325 1625);
DOT 1 (-2325 1525);
DOT 1 (-2325 1575);
DOT 1 (-2325 1425);
DOT 1 (-2325 1475);
DOT 1 (-2325 1375);
DOT 1 (-2325 1275);
DOT 1 (-2325 1175);
DOT 1 (-2325 1225);
DOT 1 (-2325 1125);
DOT 1 (-2325 1075);
DOT 1 (-2325 1025);
DOT 1 (-2325 975);
DOT 1 (-4150 4475);
DOT 1 (-4150 4525);
DOT 1 (-4150 4425);
DOT 1 (-4150 4375);
DOT 1 (-4150 4225);
DOT 1 (-4150 4275);
DOT 1 (-4150 4325);
DOT 1 (-4150 4125);
DOT 1 (-4150 4175);
DOT 1 (-4150 4075);
DOT 1 (-4150 3975);
DOT 1 (-4150 4025);
DOT 1 (-4150 3875);
DOT 1 (-4150 3825);
DOT 1 (-4150 3775);
DOT 1 (-4150 3725);
DOT 1 (-4150 3575);
DOT 1 (-4150 3675);
DOT 1 (-4150 3525);
DOT 1 (-4150 3475);
DOT 1 (-4150 3325);
DOT 1 (-4150 3375);
DOT 1 (-4150 3425);
DOT 1 (-4150 3275);
DOT 1 (-4150 3225);
DOT 1 (-4150 3125);
DOT 1 (-4150 3175);
DOT 1 (-4150 3075);
DOT 1 (-4150 2975);
DOT 1 (-4150 3025);
DOT 1 (-4150 2925);
DOT 1 (-4150 2875);
DOT 1 (-4150 2825);
DOT 1 (-4150 2775);
DOT 1 (-4150 2475);
DOT 1 (-4150 2525);
DOT 1 (-4150 2325);
DOT 1 (-4150 2175);
DOT 1 (-4150 2225);
DOT 1 (-4150 2275);
DOT 1 (-4150 2075);
DOT 1 (-4150 2125);
DOT 1 (-4150 2025);
DOT 1 (-4150 1975);
DOT 1 (-4150 1925);
DOT 1 (-4150 1825);
DOT 1 (-4150 1875);
DOT 1 (-4150 1775);
DOT 1 (-4150 1725);
DOT 1 (-4150 1675);
DOT 1 (-4150 1525);
DOT 1 (-4150 1625);
DOT 1 (-4150 1575);
DOT 1 (-4150 1425);
DOT 1 (-4150 1475);
DOT 1 (-4150 1275);
DOT 1 (-4150 1225);
DOT 1 (-4150 1175);
DOT 1 (-4150 1025);
DOT 1 (-4150 1075);
DOT 1 (-4150 1125);
DOT 1 (-4150 925);
DOT 1 (-4150 975);
DOT 1 (-4150 875);
DOT 1 (-4150 825);
DOT 1 (-4150 775);
DOT 1 (-4150 675);
DOT 1 (-4150 725);
DOT 1 (-4150 625);
DOT 1 (-5975 725);
DOT 1 (-5975 775);
DOT 1 (-5975 825);
DOT 1 (-5975 925);
DOT 1 (-5975 875);
DOT 1 (-5975 975);
DOT 1 (-5975 1025);
DOT 1 (-5975 1075);
DOT 1 (-5975 1225);
DOT 1 (-5975 1125);
DOT 1 (-5975 1175);
DOT 1 (-5975 1325);
DOT 1 (-5975 1275);
DOT 1 (-5975 1475);
DOT 1 (-5975 1375);
DOT 1 (-5975 1575);
DOT 1 (-5975 1525);
DOT 1 (-5975 1625);
DOT 1 (-5975 1825);
DOT 1 (-5975 1875);
DOT 1 (-5975 1975);
DOT 1 (-5975 2125);
DOT 1 (-5975 2175);
DOT 1 (-5975 2225);
DOT 1 (-5975 2325);
DOT 1 (-5975 2375);
DOT 1 (-5975 2425);
DOT 1 (-5975 2575);
DOT 1 (-5975 2525);
DOT 1 (-5975 2625);
DOT 1 (-5975 2725);
DOT 1 (-5975 2775);
DOT 1 (-5975 2825);
DOT 1 (-5975 2875);
DOT 1 (-5975 2925);
DOT 1 (-5975 2975);
DOT 1 (-5975 3025);
DOT 1 (-5975 3075);
DOT 1 (-5975 3125);
DOT 1 (-5975 3175);
DOT 1 (-5975 3225);
DOT 1 (-5975 3375);
DOT 1 (-5975 3325);
DOT 1 (-5975 3425);
DOT 1 (-5975 3475);
DOT 1 (-5975 3625);
DOT 1 (-5975 3775);
DOT 1 (-5975 3825);
DOT 1 (-5975 3925);
DOT 1 (-5975 4025);
DOT 1 (-5975 3975);
DOT 1 (-4450 675);
DOT 1 (-4450 625);
DOT 1 (-4450 725);
DOT 1 (-4450 775);
DOT 1 (-4450 825);
DOT 1 (-4450 875);
DOT 1 (-4450 925);
DOT 1 (-4450 975);
DOT 1 (-4450 1025);
DOT 1 (-4450 1075);
DOT 1 (-4450 1125);
DOT 1 (-4450 1175);
DOT 1 (-4450 1225);
DOT 1 (-4450 1325);
DOT 1 (-4450 1275);
DOT 1 (-4450 1425);
DOT 1 (-4450 1475);
DOT 1 (-4450 1525);
DOT 1 (-4450 1575);
DOT 1 (-4450 1625);
DOT 1 (-4450 1825);
DOT 1 (-4450 1775);
DOT 1 (-4450 1875);
DOT 1 (-4450 1925);
DOT 1 (-4450 1975);
DOT 1 (-4450 2025);
DOT 1 (-4450 2075);
DOT 1 (-4450 2125);
DOT 1 (-4450 2225);
DOT 1 (-4450 2175);
DOT 1 (-4450 2275);
DOT 1 (-4450 2325);
DOT 1 (-4450 2375);
DOT 1 (-4450 2475);
DOT 1 (-4450 2525);
DOT 1 (-4450 2575);
DOT 1 (-4450 2625);
DOT 1 (-4450 2725);
DOT 1 (-4450 2675);
DOT 1 (-4450 2775);
DOT 1 (-4450 2825);
DOT 1 (-4450 2875);
DOT 1 (-4450 2925);
DOT 1 (-4450 2975);
DOT 1 (-4450 3025);
DOT 1 (-4450 3075);
DOT 1 (-4450 3125);
DOT 1 (-4450 3175);
DOT 1 (-4450 3225);
DOT 1 (-4450 3275);
DOT 1 (-4450 3375);
DOT 1 (-4450 3325);
DOT 1 (-4450 3425);
DOT 1 (-4450 3475);
DOT 1 (-4450 3525);
DOT 1 (-4450 3625);
DOT 1 (-4450 3575);
DOT 1 (-4450 3875);
DOT 1 (-4450 3825);
DOT 1 (-4450 3925);
DOT 1 (-4450 3975);
DOT 1 (-4450 4025);
DOT 1 (-5975 4125);
DOT 1 (-5975 4075);
DOT 1 (-5975 4175);
DOT 1 (-5975 4225);
DOT 1 (-4450 4125);
DOT 1 (-4450 4175);
DOT 1 (-4450 4275);
DOT 1 (-4450 4325);
DOT 1 (-4450 4375);
DOT 1 (-4450 4425);
DOT 1 (-4450 4525);
DOT 1 (-4450 4475);
DOT 1 (-7800 625);
DOT 1 (-7800 725);
DOT 1 (-7800 675);
DOT 1 (-7800 775);
DOT 1 (-7800 825);
DOT 1 (-7800 875);
DOT 1 (-7800 975);
DOT 1 (-7800 925);
DOT 1 (-7800 1125);
DOT 1 (-7800 1075);
DOT 1 (-7800 1025);
DOT 1 (-7800 1225);
DOT 1 (-7800 1175);
DOT 1 (-7800 1375);
DOT 1 (-7800 1325);
DOT 1 (-7800 1275);
DOT 1 (-7800 1475);
DOT 1 (-7800 1425);
DOT 1 (-7800 1575);
DOT 1 (-7800 1625);
DOT 1 (-7800 1525);
DOT 1 (-7800 1675);
DOT 1 (-7800 1725);
DOT 1 (-7800 1775);
DOT 1 (-7800 1875);
DOT 1 (-7800 1825);
DOT 1 (-7800 1975);
DOT 1 (-7800 1925);
DOT 1 (-7800 2025);
DOT 1 (-7800 2125);
DOT 1 (-7800 2075);
DOT 1 (-7800 2275);
DOT 1 (-7800 2225);
DOT 1 (-7800 2175);
DOT 1 (-7800 2375);
DOT 1 (-7800 2325);
DOT 1 (-7800 2425);
DOT 1 (-7800 2475);
DOT 1 (-7800 2625);
DOT 1 (-7800 2575);
DOT 1 (-7800 2675);
DOT 1 (-7800 2775);
DOT 1 (-7800 2725);
DOT 1 (-7800 2875);
DOT 1 (-7800 2825);
DOT 1 (-7800 2925);
DOT 1 (-7800 3025);
DOT 1 (-7800 2975);
DOT 1 (-7800 3175);
DOT 1 (-7800 3075);
DOT 1 (-7800 3125);
DOT 1 (-7800 3275);
DOT 1 (-7800 3225);
DOT 1 (-7800 3425);
DOT 1 (-7800 3375);
DOT 1 (-7800 3325);
DOT 1 (-7800 3525);
DOT 1 (-7800 3475);
DOT 1 (-7800 3675);
DOT 1 (-7800 3625);
DOT 1 (-7800 3575);
DOT 1 (-7800 3775);
DOT 1 (-7800 3725);
DOT 1 (-7800 3825);
DOT 1 (-7800 3875);
DOT 1 (-7800 4025);
DOT 1 (-7800 3975);
DOT 1 (-6275 625);
DOT 1 (-6275 725);
DOT 1 (-6275 675);
DOT 1 (-6275 775);
DOT 1 (-6275 825);
DOT 1 (-6275 975);
DOT 1 (-6275 925);
DOT 1 (-6275 1025);
DOT 1 (-6275 1075);
DOT 1 (-6275 1125);
DOT 1 (-6275 1225);
DOT 1 (-6275 1175);
DOT 1 (-6275 1325);
DOT 1 (-6275 1375);
DOT 1 (-6275 1475);
DOT 1 (-6275 1425);
DOT 1 (-6275 1525);
DOT 1 (-6275 1575);
DOT 1 (-6275 1725);
DOT 1 (-6275 1675);
DOT 1 (-6275 1775);
DOT 1 (-6275 1825);
DOT 1 (-6275 1875);
DOT 1 (-6275 1925);
DOT 1 (-6275 1975);
DOT 1 (-6275 2025);
DOT 1 (-6275 2075);
DOT 1 (-6275 2275);
DOT 1 (-6275 2175);
DOT 1 (-6275 2325);
DOT 1 (-6275 2375);
DOT 1 (-6275 2525);
DOT 1 (-6275 2475);
DOT 1 (-6275 2425);
DOT 1 (-6275 2575);
DOT 1 (-6275 2675);
DOT 1 (-6275 2775);
DOT 1 (-6275 2725);
DOT 1 (-6275 2875);
DOT 1 (-6275 2925);
DOT 1 (-6275 3025);
DOT 1 (-6275 2975);
DOT 1 (-6275 3075);
DOT 1 (-6275 3225);
DOT 1 (-6275 3425);
DOT 1 (-6275 3375);
DOT 1 (-6275 3325);
DOT 1 (-6275 3525);
DOT 1 (-6275 3475);
DOT 1 (-6275 3575);
DOT 1 (-6275 3775);
DOT 1 (-6275 3725);
DOT 1 (-6275 3825);
DOT 1 (-6275 3925);
DOT 1 (-7800 4075);
DOT 1 (-7800 4175);
DOT 1 (-7800 4125);
DOT 1 (-7800 4225);
DOT 1 (-7800 4425);
DOT 1 (-7800 4375);
DOT 1 (-7800 4525);
DOT 1 (-7800 4475);
DOT 1 (-6275 4275);
DOT 1 (-6275 4225);
DOT 1 (-6275 4375);
DOT 1 (-4450 2425);
DOT 1 (-6275 4475);
DOT 1 (-5975 625);
DOT 1 (-6275 3125);
DOT 1 (-7800 3925);
DOT 1 (-5975 3675);
DOT 1 (-5975 1425);
DOT 1 (-7800 2525);
DOT 1 (-6275 2225);
DOT 1 (-5975 4525);
DOT 1 (-6275 3875);
DOT 1 (-6275 3675);
DOT 1 (-6275 4125);
DOT 1 (-6275 4025);
DOT 1 (-2325 3275);
DOT 1 (-775 3625);
DOT 1 (-4450 4075);
DOT 1 (-6275 4425);
DOT 1 (-7800 4275);
FORCENOTE
SKYLAKE - SKT0 - 20 OF 21
(-1975 175) 0;
DISPLAY LEFT (-1975 175);
DISPLAY 1.021277 (-1975 175);
PAINT RED (-1975 175);
FORCENOTE
BOM_COST=PROC_SOCKET
(-8225 200) 0;
DISPLAY LEFT (-8225 200);
DISPLAY 1.382979 (-8225 200);
PAINT PURPLE (-8225 200);
FORCENOTE
ROOM=CPU0
(-8150 325) 0;
DISPLAY LEFT (-8150 325);
DISPLAY 1.382979 (-8150 325);
PAINT PURPLE (-8150 325);
QUIT
